FILE_TYPE = MACRO_DRAWING;
SET COLOR_WIRE YELLOW;
SET COLOR_PROP MONO;
SET COLOR_DOT WHITE;
SET COLOR_ARC YELLOW;
SET COLOR_BODY GREEN;
SET COLOR_NOTE MONO;
SET PROP_DISPLAY VALUE;
SET PAGE_NUMBER P221;
FORCEADD MIC5166..1
(1550 1050);
FORCEPROP 2 LASTPIN (1250 950) $PN 6
J 2
(1240 960);
DISPLAY 0.617021 (1240 960);
PAINT ORANGE (1240 960);
FORCEPROP 2 LASTPIN (1250 800) $PN 2
J 2
(1240 810);
DISPLAY 0.617021 (1240 810);
PAINT ORANGE (1240 810);
FORCEPROP 1 LAST PART_NUMBER H55101-001
J 0
(1300 650);
DISPLAY 0.617021 (1300 650);
PAINT BLUE (1300 650);
FORCEPROP 2 LASTPIN (1850 750) $PN 11
J 0
(1860 760);
DISPLAY 0.617021 (1860 760);
PAINT ORANGE (1860 760);
FORCEPROP 2 LASTPIN (1850 850) $PN 3
J 0
(1860 860);
DISPLAY 0.617021 (1860 860);
PAINT ORANGE (1860 860);
FORCEPROP 2 LASTPIN (1850 900) $PN 8
J 0
(1860 910);
DISPLAY 0.617021 (1860 910);
PAINT ORANGE (1860 910);
FORCEPROP 2 LASTPIN (1850 1000) $PN 5
J 0
(1860 1010);
DISPLAY 0.617021 (1860 1010);
PAINT ORANGE (1860 1010);
FORCEPROP 2 LASTPIN (1250 1300) $PN 10
J 2
(1240 1310);
DISPLAY 0.617021 (1240 1310);
PAINT ORANGE (1240 1310);
FORCEPROP 2 LASTPIN (1250 1150) $PN 4
J 2
(1240 1160);
DISPLAY 0.617021 (1240 1160);
PAINT ORANGE (1240 1160);
FORCEPROP 2 LASTPIN (1250 1050) $PN 7
J 2
(1240 1060);
DISPLAY 0.617021 (1240 1060);
PAINT ORANGE (1240 1060);
FORCEPROP 1 LAST MATERIAL IC
J 0
(1300 1425);
DISPLAY 0.617021 (1300 1425);
PAINT SKYBLUE (1300 1425);
FORCEPROP 1 LAST LOCATION EU4G3
J 0
(1300 1475);
DISPLAY 0.617021 (1300 1475);
PAINT AQUA (1300 1475);
FORCEPROP 2 LASTPIN (1850 1300) $PN 9
J 0
(1860 1310);
DISPLAY 0.617021 (1860 1310);
PAINT ORANGE (1860 1310);
FORCEPROP 2 LASTPIN (1850 1200) $PN 1
J 0
(1860 1210);
DISPLAY 0.617021 (1860 1210);
PAINT ORANGE (1860 1210);
FORCEPROP 2 LAST CDS_LOCATION EU4G3
J 0
(1300 1475);
DISPLAY 0.617021 (1300 1475);
PAINT AQUA (1300 1475);
DISPLAY INVISIBLE (1300 1475);
FORCEPROP 2 LAST SEC_TYPE DFN
J 0
(1300 1525);
DISPLAY 1.021277 (1300 1525);
PAINT ORANGE (1300 1525);
DISPLAY INVISIBLE (1300 1525);
FORCEPROP 2 LAST SEC 1
J 0
(1300 1525);
DISPLAY 0.680851 (1300 1525);
PAINT MONO (1300 1525);
DISPLAY INVISIBLE (1300 1525);
FORCEPROP 2 LAST ROOM VTT_ABC_PWR_VR
J 0
(1300 1522);
DISPLAY 1.021277 (1300 1522);
PAINT ORANGE (1300 1522);
DISPLAY INVISIBLE (1300 1522);
FORCEPROP 1 LAST PACK_TYPE DFN
J 0
(1300 1525);
PAINT SKYBLUE (1300 1525);
DISPLAY INVISIBLE (1300 1525);
FORCEPROP 2 LAST BOM_COST MEM_VRD_VTT_ABC
J 0
(1300 1570);
DISPLAY 1.021277 (1300 1570);
PAINT ORANGE (1300 1570);
DISPLAY INVISIBLE (1300 1570);
FORCEPROP 1 LAST CDS_LMAN_SYM_OUTLINE -250,350,250,-350
J 0
(1550 1050);
DISPLAY 0.468085 (1550 1050);
PAINT GREEN (1550 1050);
DISPLAY INVISIBLE (1550 1050);
FORCEPROP 2 LAST CDS_LIB mstr_vreg
J 0
(1550 1050);
PAINT ORANGE (1550 1050);
DISPLAY INVISIBLE (1550 1050);
FORCEPROP 1 LAST PATH I1
J 0
(1750 1425);
PAINT GREEN (1750 1425);
DISPLAY INVISIBLE (1750 1425);
FORCEADD PVTT_ABC..1
(3600 3725);
FORCEPROP 3 LASTPIN (3600 3675) SIG_NAME PVTT_ABC\g
J 0
(3610 3685);
DISPLAY 0.659574 (3610 3685);
PAINT MONO (3610 3685);
DISPLAY INVISIBLE (3610 3685);
FORCEPROP 1 LAST BODY_TYPE PLUMBING
J 0
(3555 3682);
DISPLAY 0.340426 (3555 3682);
PAINT GREEN (3555 3682);
DISPLAY INVISIBLE (3555 3682);
FORCEPROP 1 LAST VOLTAGE 0.6V
J 0
(3555 3682);
DISPLAY 0.340426 (3555 3682);
PAINT SKYBLUE (3555 3682);
DISPLAY INVISIBLE (3555 3682);
FORCEPROP 1 LAST HDL_POWER PVTT_ABC
J 1
(3600 3775);
DISPLAY 0.872340 (3600 3775);
PAINT GREEN (3600 3775);
DISPLAY INVISIBLE (3600 3775);
FORCEPROP 1 LAST PATH I11
J 0
(3650 3750);
DISPLAY 0.872340 (3650 3750);
PAINT AQUA (3650 3750);
DISPLAY INVISIBLE (3650 3750);
FORCEPROP 2 LAST CDS_LIB mstr_symbols
J 0
(3600 3725);
PAINT ORANGE (3600 3725);
DISPLAY INVISIBLE (3600 3725);
FORCEPROP 2 LAST BOM_COST MEM_VRD_PVDDQ_AB
J 0
(3675 3825);
PAINT MONO (3675 3825);
DISPLAY INVISIBLE (3675 3825);
FORCEPROP 2 LAST ROOM VTT_ABC_PWR_VR
J 0
(3850 3825);
PAINT ORANGE (3850 3825);
DISPLAY INVISIBLE (3850 3825);
FORCEADD GND..1
(3875 1375);
FORCEPROP 3 LASTPIN (3875 1425) SIG_NAME GND\g
J 0
(3885 1435);
DISPLAY 0.659574 (3885 1435);
PAINT MONO (3885 1435);
DISPLAY INVISIBLE (3885 1435);
FORCEPROP 1 LAST BODY_TYPE PLUMBING
J 0
(3830 1332);
DISPLAY 0.340426 (3830 1332);
PAINT GREEN (3830 1332);
DISPLAY INVISIBLE (3830 1332);
FORCEPROP 1 LAST VOLTAGE 0.0V
J 0
(3830 1332);
DISPLAY 0.340426 (3830 1332);
PAINT SKYBLUE (3830 1332);
DISPLAY INVISIBLE (3830 1332);
FORCEPROP 1 LAST PATH I14
J 0
(3950 1375);
DISPLAY 0.872340 (3950 1375);
PAINT AQUA (3950 1375);
DISPLAY INVISIBLE (3950 1375);
FORCEPROP 2 LAST CDS_LIB mstr_symbols
J 0
(3875 1375);
DISPLAY 0.744681 (3875 1375);
PAINT MONO (3875 1375);
DISPLAY INVISIBLE (3875 1375);
FORCEPROP 1 LAST SIZE 1B
J 0
(3950 1325);
DISPLAY 0.893617 (3950 1325);
PAINT GREEN (3950 1325);
DISPLAY INVISIBLE (3950 1325);
FORCEPROP 1 LAST HDL_POWER GND
J 0
(3875 1525);
DISPLAY 0.893617 (3875 1525);
PAINT GREEN (3875 1525);
DISPLAY INVISIBLE (3875 1525);
FORCEADD CAP..1
(3875 1600);
FORCEPROP 1 LASTPIN (3875 1500) $PN 2
J 0
(3885 1480);
DISPLAY 0.617021 (3885 1480);
PAINT WHITE (3885 1480);
FORCEPROP 1 LAST MATERIAL X7R
J 0
(3925 1500);
DISPLAY 0.617021 (3925 1500);
PAINT SKYBLUE (3925 1500);
FORCEPROP 1 LASTPIN (3875 1700) $PN 1
J 0
(3885 1680);
DISPLAY 0.617021 (3885 1680);
PAINT WHITE (3885 1680);
FORCEPROP 1 LAST VOLTAGE 50V
J 0
(3925 1600);
DISPLAY 0.617021 (3925 1600);
PAINT SKYBLUE (3925 1600);
FORCEPROP 1 LAST TOLERANCE 10%
J 0
(3925 1550);
DISPLAY 0.617021 (3925 1550);
PAINT SKYBLUE (3925 1550);
FORCEPROP 1 LAST LOCATION C4G14
J 0
(3925 1700);
DISPLAY 0.617021 (3925 1700);
PAINT AQUA (3925 1700);
FORCEPROP 1 LAST PACK_TYPE 0402LF
J 0
(3925 1400);
DISPLAY 0.617021 (3925 1400);
PAINT SKYBLUE (3925 1400);
FORCEPROP 1 LAST VALUE 1000PF
J 0
(3925 1650);
DISPLAY 0.617021 (3925 1650);
PAINT SKYBLUE (3925 1650);
FORCEPROP 1 LAST PART_NUMBER A36096-046
J 0
(3925 1450);
DISPLAY 0.617021 (3925 1450);
PAINT BLUE (3925 1450);
FORCEPROP 2 LAST CDS_LIB mstr_discrete
J 0
(3875 1600);
DISPLAY 0.744681 (3875 1600);
PAINT MONO (3875 1600);
DISPLAY INVISIBLE (3875 1600);
FORCEPROP 2 LAST CDS_LOCATION C4G14
J 0
(3925 1700);
DISPLAY 0.617021 (3925 1700);
PAINT AQUA (3925 1700);
DISPLAY INVISIBLE (3925 1700);
FORCEPROP 1 LAST PATH I15
J 0
(3925 1750);
DISPLAY 0.978723 (3925 1750);
PAINT WHITE (3925 1750);
DISPLAY INVISIBLE (3925 1750);
FORCEPROP 2 LAST ROOM VTT_ABC_PWR_VR
J 0
(3925 1750);
DISPLAY 1.021277 (3925 1750);
PAINT ORANGE (3925 1750);
DISPLAY INVISIBLE (3925 1750);
FORCEPROP 2 LAST BOM_COST MEM_VRD_VTT_ABC
J 0
(3925 1800);
DISPLAY 1.021277 (3925 1800);
PAINT ORANGE (3925 1800);
DISPLAY INVISIBLE (3925 1800);
FORCEPROP 2 LAST SEC_TYPE 0402LF
J 0
(3925 1800);
DISPLAY 1.021277 (3925 1800);
PAINT ORANGE (3925 1800);
DISPLAY INVISIBLE (3925 1800);
FORCEPROP 2 LAST SEC 1
J 0
(3925 1800);
DISPLAY 0.680851 (3925 1800);
PAINT MONO (3925 1800);
DISPLAY INVISIBLE (3925 1800);
FORCEADD GND..1
(3975 600);
FORCEPROP 3 LASTPIN (3975 650) SIG_NAME GND\g
J 0
(3985 660);
DISPLAY 0.659574 (3985 660);
PAINT MONO (3985 660);
DISPLAY INVISIBLE (3985 660);
FORCEPROP 2 LAST CDS_LIB mstr_symbols
J 0
(3975 600);
PAINT ORANGE (3975 600);
DISPLAY INVISIBLE (3975 600);
FORCEPROP 1 LAST SIZE 1B
J 0
(4050 550);
DISPLAY 0.893617 (4050 550);
PAINT GREEN (4050 550);
DISPLAY INVISIBLE (4050 550);
FORCEPROP 1 LAST BODY_TYPE PLUMBING
J 0
(3930 557);
DISPLAY 0.340426 (3930 557);
PAINT GREEN (3930 557);
DISPLAY INVISIBLE (3930 557);
FORCEPROP 1 LAST PATH I19
J 0
(4050 600);
DISPLAY 0.872340 (4050 600);
PAINT AQUA (4050 600);
DISPLAY INVISIBLE (4050 600);
FORCEPROP 1 LAST VOLTAGE 0.0V
J 0
(3930 557);
DISPLAY 0.340426 (3930 557);
PAINT SKYBLUE (3930 557);
DISPLAY INVISIBLE (3930 557);
FORCEPROP 1 LAST HDL_POWER GND
J 0
(3975 750);
DISPLAY 0.893617 (3975 750);
PAINT GREEN (3975 750);
DISPLAY INVISIBLE (3975 750);
FORCEADD CAP..1
(3975 1025);
FORCEPROP 1 LASTPIN (3975 925) $PN 2
J 0
(3985 905);
DISPLAY 0.617021 (3985 905);
PAINT WHITE (3985 905);
FORCEPROP 1 LAST PART_NUMBER C95333-002
R 1
J 0
(3925 875);
DISPLAY 0.617021 (3925 875);
PAINT BLUE (3925 875);
FORCEPROP 1 LASTPIN (3975 1125) $PN 1
J 0
(3985 1105);
DISPLAY 0.617021 (3985 1105);
PAINT WHITE (3985 1105);
FORCEPROP 1 LAST VOLTAGE 4V
J 0
(4025 1025);
DISPLAY 0.617021 (4025 1025);
PAINT SKYBLUE (4025 1025);
FORCEPROP 1 LAST MATERIAL X6S
J 0
(4025 925);
DISPLAY 0.617021 (4025 925);
PAINT SKYBLUE (4025 925);
FORCEPROP 1 LAST PACK_TYPE 0805LF
J 0
(4025 875);
DISPLAY 0.617021 (4025 875);
PAINT SKYBLUE (4025 875);
FORCEPROP 1 LAST TOLERANCE 20%
J 0
(4025 975);
DISPLAY 0.617021 (4025 975);
PAINT SKYBLUE (4025 975);
FORCEPROP 1 LAST VALUE 22UF
J 0
(4025 1075);
DISPLAY 0.617021 (4025 1075);
PAINT SKYBLUE (4025 1075);
FORCEPROP 1 LAST LOCATION C4G24
J 0
(4025 1125);
DISPLAY 0.617021 (4025 1125);
PAINT AQUA (4025 1125);
FORCEPROP 2 LAST BOM_COST MEM_VRD_VTT_ABC
J 0
(4045 1230);
DISPLAY 1.021277 (4045 1230);
PAINT ORANGE (4045 1230);
DISPLAY INVISIBLE (4045 1230);
FORCEPROP 2 LAST CDS_LIB mstr_discrete
J 0
(3975 1025);
PAINT ORANGE (3975 1025);
DISPLAY INVISIBLE (3975 1025);
FORCEPROP 2 LAST SEC 1
J 0
(4026 1245);
DISPLAY 0.680851 (4026 1245);
PAINT MONO (4026 1245);
DISPLAY INVISIBLE (4026 1245);
FORCEPROP 2 LAST CDS_LOCATION C4G24
J 0
(4025 1125);
DISPLAY 0.617021 (4025 1125);
PAINT AQUA (4025 1125);
DISPLAY INVISIBLE (4025 1125);
FORCEPROP 1 LAST PATH I20
J 0
(4025 1175);
DISPLAY 0.978723 (4025 1175);
PAINT WHITE (4025 1175);
DISPLAY INVISIBLE (4025 1175);
FORCEPROP 2 LAST ROOM VTT_ABC_PWR_VR
J 0
(4045 1180);
DISPLAY 1.021277 (4045 1180);
PAINT ORANGE (4045 1180);
DISPLAY INVISIBLE (4045 1180);
FORCEPROP 2 LAST SEC_TYPE 0805LF
J 0
(4026 1245);
DISPLAY 1.021277 (4026 1245);
PAINT ORANGE (4026 1245);
DISPLAY INVISIBLE (4026 1245);
FORCEADD CAP..1
(475 2350);
FORCEPROP 1 LASTPIN (475 2250) $PN 2
J 0
(485 2230);
DISPLAY 0.617021 (485 2230);
PAINT WHITE (485 2230);
FORCEPROP 1 LASTPIN (475 2450) $PN 1
J 0
(485 2430);
DISPLAY 0.617021 (485 2430);
PAINT WHITE (485 2430);
FORCEPROP 1 LAST LOCATION C6U16
J 0
(525 2450);
DISPLAY 0.617021 (525 2450);
PAINT AQUA (525 2450);
FORCEPROP 1 LAST PART_NUMBER E15431-001
J 0
(525 2200);
DISPLAY 0.617021 (525 2200);
PAINT BLUE (525 2200);
FORCEPROP 1 LAST VALUE 10UF
J 0
(525 2400);
DISPLAY 0.617021 (525 2400);
PAINT SKYBLUE (525 2400);
FORCEPROP 1 LAST TOLERANCE 20%
J 0
(525 2300);
DISPLAY 0.617021 (525 2300);
PAINT SKYBLUE (525 2300);
FORCEPROP 1 LAST PACK_TYPE 0603LF
J 0
(525 2150);
DISPLAY 0.617021 (525 2150);
PAINT SKYBLUE (525 2150);
FORCEPROP 1 LAST VOLTAGE 4V
J 0
(525 2350);
DISPLAY 0.617021 (525 2350);
PAINT SKYBLUE (525 2350);
FORCEPROP 1 LAST MATERIAL X6S
J 0
(525 2250);
DISPLAY 0.617021 (525 2250);
PAINT SKYBLUE (525 2250);
FORCEPROP 2 LAST CDS_LIB mstr_discrete
J 0
(475 2350);
PAINT ORANGE (475 2350);
DISPLAY INVISIBLE (475 2350);
FORCEPROP 2 LAST ROOM VTT_ABC_PWR_VR
J 0
(525 2500);
DISPLAY 1.021277 (525 2500);
PAINT ORANGE (525 2500);
DISPLAY INVISIBLE (525 2500);
FORCEPROP 1 LAST PATH I22
J 0
(525 2500);
DISPLAY 0.978723 (525 2500);
PAINT WHITE (525 2500);
DISPLAY INVISIBLE (525 2500);
FORCEPROP 2 LAST CDS_LOCATION C6U16
J 0
(525 2450);
DISPLAY 0.617021 (525 2450);
PAINT AQUA (525 2450);
DISPLAY INVISIBLE (525 2450);
FORCEPROP 2 LAST BOM_COST MEM_VRD_VTT_ABC
J 0
(525 2550);
DISPLAY 1.021277 (525 2550);
PAINT ORANGE (525 2550);
DISPLAY INVISIBLE (525 2550);
FORCEPROP 2 LAST SEC 1
J 0
(531 2565);
DISPLAY 0.680851 (531 2565);
PAINT MONO (531 2565);
DISPLAY INVISIBLE (531 2565);
FORCEPROP 2 LAST SEC_TYPE 0603LF
J 0
(531 2565);
DISPLAY 1.021277 (531 2565);
PAINT ORANGE (531 2565);
DISPLAY INVISIBLE (531 2565);
FORCEADD GND..1
(475 2100);
FORCEPROP 3 LASTPIN (475 2150) SIG_NAME GND\g
J 0
(485 2160);
DISPLAY 0.659574 (485 2160);
PAINT MONO (485 2160);
DISPLAY INVISIBLE (485 2160);
FORCEPROP 2 LAST BOM_COST MEM_VRD_VTT_ABC
J 0
(-30 2230);
DISPLAY 1.021277 (-30 2230);
PAINT ORANGE (-30 2230);
DISPLAY INVISIBLE (-30 2230);
FORCEPROP 2 LAST ROOM VTT_ABC_PWR_VR
J 0
(-30 2180);
DISPLAY 1.021277 (-30 2180);
PAINT ORANGE (-30 2180);
DISPLAY INVISIBLE (-30 2180);
FORCEPROP 2 LAST CDS_LIB mstr_symbols
J 0
(475 2100);
PAINT MONO (475 2100);
DISPLAY INVISIBLE (475 2100);
FORCEPROP 1 LAST BODY_TYPE PLUMBING
J 0
(430 2057);
DISPLAY 0.340426 (430 2057);
PAINT GREEN (430 2057);
DISPLAY INVISIBLE (430 2057);
FORCEPROP 1 LAST HDL_POWER GND
J 0
(475 2250);
DISPLAY 0.893617 (475 2250);
PAINT GREEN (475 2250);
DISPLAY INVISIBLE (475 2250);
FORCEPROP 1 LAST VOLTAGE 0.0V
J 0
(430 2057);
DISPLAY 0.340426 (430 2057);
PAINT SKYBLUE (430 2057);
DISPLAY INVISIBLE (430 2057);
FORCEPROP 1 LAST PATH I23
J 0
(550 2100);
DISPLAY 0.872340 (550 2100);
PAINT AQUA (550 2100);
DISPLAY INVISIBLE (550 2100);
FORCEPROP 1 LAST SIZE 1B
J 0
(550 2050);
DISPLAY 0.893617 (550 2050);
PAINT GREEN (550 2050);
DISPLAY INVISIBLE (550 2050);
FORCEADD CAP..1
(475 1475);
FORCEPROP 1 LASTPIN (475 1375) $PN 2
J 0
(485 1355);
DISPLAY 0.617021 (485 1355);
PAINT WHITE (485 1355);
FORCEPROP 1 LASTPIN (475 1575) $PN 1
J 0
(485 1555);
DISPLAY 0.617021 (485 1555);
PAINT WHITE (485 1555);
FORCEPROP 1 LAST PART_NUMBER D97712-011
J 0
(525 1425);
DISPLAY 0.617021 (525 1425);
PAINT BLUE (525 1425);
FORCEPROP 1 LAST TOLERANCE 10%
J 0
(525 1475);
DISPLAY 0.617021 (525 1475);
PAINT SKYBLUE (525 1475);
FORCEPROP 1 LAST PACK_TYPE 0402
J 0
(525 1375);
DISPLAY 0.617021 (525 1375);
PAINT SKYBLUE (525 1375);
FORCEPROP 1 LAST MATERIAL X6S
J 0
(650 1475);
DISPLAY 0.617021 (650 1475);
PAINT SKYBLUE (650 1475);
FORCEPROP 1 LAST VALUE 1.0UF
J 0
(525 1525);
DISPLAY 0.617021 (525 1525);
PAINT SKYBLUE (525 1525);
FORCEPROP 1 LAST VOLTAGE 16V
J 0
(675 1525);
DISPLAY 0.617021 (675 1525);
PAINT SKYBLUE (675 1525);
FORCEPROP 1 LAST LOCATION C4G15
J 0
(525 1575);
DISPLAY 0.617021 (525 1575);
PAINT AQUA (525 1575);
FORCEPROP 2 LAST CDS_LIB mstr_discrete
J 0
(475 1475);
PAINT ORANGE (475 1475);
DISPLAY INVISIBLE (475 1475);
FORCEPROP 2 LAST ROOM VTT_ABC_PWR_VR
J 0
(525 1625);
DISPLAY 1.021277 (525 1625);
PAINT ORANGE (525 1625);
DISPLAY INVISIBLE (525 1625);
FORCEPROP 1 LAST PATH I24
J 0
(525 1625);
DISPLAY 0.978723 (525 1625);
PAINT WHITE (525 1625);
DISPLAY INVISIBLE (525 1625);
FORCEPROP 2 LAST CDS_LOCATION C4G15
J 0
(525 1575);
DISPLAY 0.617021 (525 1575);
PAINT AQUA (525 1575);
DISPLAY INVISIBLE (525 1575);
FORCEPROP 2 LAST $SEC 1
J 0
(525 1671);
DISPLAY 0.680851 (525 1671);
PAINT MONO (525 1671);
DISPLAY INVISIBLE (525 1671);
FORCEPROP 2 LAST CDS_SEC 1
J 0
(525 1671);
DISPLAY 1.021277 (525 1671);
PAINT ORANGE (525 1671);
DISPLAY INVISIBLE (525 1671);
FORCEPROP 2 LAST BOM_COST MEM_VRD_VTT_ABC
J 0
(525 1675);
DISPLAY 1.021277 (525 1675);
PAINT ORANGE (525 1675);
DISPLAY INVISIBLE (525 1675);
FORCEADD GND..1
(475 1250);
FORCEPROP 3 LASTPIN (475 1300) SIG_NAME GND\g
J 0
(485 1310);
DISPLAY 0.659574 (485 1310);
PAINT MONO (485 1310);
DISPLAY INVISIBLE (485 1310);
FORCEPROP 1 LAST VOLTAGE 0.0V
J 0
(430 1207);
DISPLAY 0.340426 (430 1207);
PAINT SKYBLUE (430 1207);
DISPLAY INVISIBLE (430 1207);
FORCEPROP 1 LAST BODY_TYPE PLUMBING
J 0
(430 1207);
DISPLAY 0.340426 (430 1207);
PAINT GREEN (430 1207);
DISPLAY INVISIBLE (430 1207);
FORCEPROP 2 LAST CDS_LIB mstr_symbols
J 0
(475 1250);
DISPLAY 0.744681 (475 1250);
PAINT MONO (475 1250);
DISPLAY INVISIBLE (475 1250);
FORCEPROP 1 LAST HDL_POWER GND
J 0
(475 1400);
DISPLAY 0.893617 (475 1400);
PAINT GREEN (475 1400);
DISPLAY INVISIBLE (475 1400);
FORCEPROP 1 LAST PATH I25
J 0
(550 1250);
DISPLAY 0.872340 (550 1250);
PAINT AQUA (550 1250);
DISPLAY INVISIBLE (550 1250);
FORCEPROP 1 LAST SIZE 1B
J 0
(550 1200);
DISPLAY 0.893617 (550 1200);
PAINT GREEN (550 1200);
DISPLAY INVISIBLE (550 1200);
FORCEADD CAP..1
(50 2325);
FORCEPROP 1 LASTPIN (50 2225) $PN 2
J 0
(60 2205);
DISPLAY 0.617021 (60 2205);
PAINT WHITE (60 2205);
FORCEPROP 1 LAST MATERIAL X6S
J 0
(100 2225);
DISPLAY 0.617021 (100 2225);
PAINT SKYBLUE (100 2225);
FORCEPROP 1 LAST TOLERANCE 20%
J 0
(100 2275);
DISPLAY 0.617021 (100 2275);
PAINT SKYBLUE (100 2275);
FORCEPROP 1 LASTPIN (50 2425) $PN 1
J 0
(60 2405);
DISPLAY 0.617021 (60 2405);
PAINT WHITE (60 2405);
FORCEPROP 1 LAST LOCATION C6U15
J 0
(100 2425);
DISPLAY 0.617021 (100 2425);
PAINT AQUA (100 2425);
FORCEPROP 1 LAST VALUE 10UF
J 0
(100 2375);
DISPLAY 0.617021 (100 2375);
PAINT SKYBLUE (100 2375);
FORCEPROP 1 LAST VOLTAGE 4V
J 0
(100 2325);
DISPLAY 0.617021 (100 2325);
PAINT SKYBLUE (100 2325);
FORCEPROP 1 LAST PACK_TYPE 0603LF
J 0
(100 2125);
DISPLAY 0.617021 (100 2125);
PAINT SKYBLUE (100 2125);
FORCEPROP 1 LAST PART_NUMBER E15431-001
J 0
(100 2175);
DISPLAY 0.617021 (100 2175);
PAINT BLUE (100 2175);
FORCEPROP 2 LAST CDS_LIB mstr_discrete
J 0
(50 2325);
PAINT ORANGE (50 2325);
DISPLAY INVISIBLE (50 2325);
FORCEPROP 2 LAST CDS_LOCATION C6U15
J 0
(100 2425);
DISPLAY 0.617021 (100 2425);
PAINT AQUA (100 2425);
DISPLAY INVISIBLE (100 2425);
FORCEPROP 1 LAST PATH I26
J 0
(100 2475);
DISPLAY 0.978723 (100 2475);
PAINT WHITE (100 2475);
DISPLAY INVISIBLE (100 2475);
FORCEPROP 2 LAST ROOM VTT_ABC_PWR_VR
J 0
(100 2475);
DISPLAY 1.021277 (100 2475);
PAINT ORANGE (100 2475);
DISPLAY INVISIBLE (100 2475);
FORCEPROP 2 LAST BOM_COST MEM_VRD_VTT_ABC
J 0
(100 2525);
DISPLAY 1.021277 (100 2525);
PAINT ORANGE (100 2525);
DISPLAY INVISIBLE (100 2525);
FORCEPROP 2 LAST SEC_TYPE 0603LF
J 0
(106 2540);
DISPLAY 1.021277 (106 2540);
PAINT ORANGE (106 2540);
DISPLAY INVISIBLE (106 2540);
FORCEPROP 2 LAST SEC 1
J 0
(106 2540);
DISPLAY 0.680851 (106 2540);
PAINT MONO (106 2540);
DISPLAY INVISIBLE (106 2540);
FORCEADD RES..1
(125 1750);
FORCEPROP 1 LAST WATTAGE 1/16W
J 2
(100 1600);
DISPLAY 0.617021 (100 1600);
PAINT SKYBLUE (100 1600);
FORCEPROP 1 LAST PART_NUMBER G21497-005
J 0
(0 1700);
DISPLAY 0.617021 (0 1700);
PAINT BLUE (0 1700);
FORCEPROP 1 LASTPIN (25 1750) $PN 1
J 0
(37 1762);
DISPLAY 0.617021 (37 1762);
PAINT WHITE (37 1762);
FORCEPROP 1 LAST VALUE 0.0
J 2
(100 1650);
DISPLAY 0.617021 (100 1650);
PAINT SKYBLUE (100 1650);
FORCEPROP 1 LAST TOLERANCE 5%
J 0
(125 1650);
DISPLAY 0.617021 (125 1650);
PAINT SKYBLUE (125 1650);
FORCEPROP 1 LAST MATERIAL CHIP
J 0
(125 1600);
DISPLAY 0.617021 (125 1600);
PAINT SKYBLUE (125 1600);
FORCEPROP 1 LAST PACK_TYPE 0402
J 0
(50 1550);
DISPLAY 0.617021 (50 1550);
PAINT SKYBLUE (50 1550);
FORCEPROP 1 LASTPIN (225 1750) $PN 2
J 0
(187 1762);
DISPLAY 0.617021 (187 1762);
PAINT WHITE (187 1762);
FORCEPROP 1 LAST LOCATION R6U4
J 0
(75 1800);
DISPLAY 0.617021 (75 1800);
PAINT AQUA (75 1800);
FORCEPROP 2 LAST CDS_LIB mstr_discrete
J 0
(125 1750);
DISPLAY 0.744681 (125 1750);
PAINT MONO (125 1750);
DISPLAY INVISIBLE (125 1750);
FORCEPROP 1 LAST PATH I28
J 0
(75 1900);
DISPLAY 0.978723 (75 1900);
PAINT WHITE (75 1900);
DISPLAY INVISIBLE (75 1900);
FORCEPROP 2 LAST BOM_COST MEM_VRD_VTT_ABC
J 0
(85 1885);
DISPLAY 1.021277 (85 1885);
PAINT ORANGE (85 1885);
DISPLAY INVISIBLE (85 1885);
FORCEPROP 2 LAST SEC_TYPE 0402
J 0
(91 1950);
DISPLAY 1.021277 (91 1950);
PAINT ORANGE (91 1950);
DISPLAY INVISIBLE (91 1950);
FORCEPROP 2 LAST CDS_LOCATION R6U4
J 0
(75 1800);
DISPLAY 0.617021 (75 1800);
PAINT AQUA (75 1800);
DISPLAY INVISIBLE (75 1800);
FORCEPROP 2 LAST SEC 1
J 0
(91 1950);
DISPLAY 0.680851 (91 1950);
PAINT MONO (91 1950);
DISPLAY INVISIBLE (91 1950);
FORCEPROP 2 LAST ROOM VTT_ABC_PWR_VR
J 0
(85 1835);
DISPLAY 1.021277 (85 1835);
PAINT ORANGE (85 1835);
DISPLAY INVISIBLE (85 1835);
FORCEADD GND..1
(50 2100);
FORCEPROP 3 LASTPIN (50 2150) SIG_NAME GND\g
J 0
(60 2160);
DISPLAY 0.659574 (60 2160);
PAINT MONO (60 2160);
DISPLAY INVISIBLE (60 2160);
FORCEPROP 2 LAST BOM_COST MEM_VRD_VTT_ABC
J 0
(-455 2230);
DISPLAY 1.021277 (-455 2230);
PAINT ORANGE (-455 2230);
DISPLAY INVISIBLE (-455 2230);
FORCEPROP 2 LAST ROOM VTT_ABC_PWR_VR
J 0
(-455 2180);
DISPLAY 1.021277 (-455 2180);
PAINT ORANGE (-455 2180);
DISPLAY INVISIBLE (-455 2180);
FORCEPROP 1 LAST SIZE 1B
J 0
(125 2050);
DISPLAY 0.893617 (125 2050);
PAINT GREEN (125 2050);
DISPLAY INVISIBLE (125 2050);
FORCEPROP 2 LAST CDS_LIB mstr_symbols
J 0
(50 2100);
DISPLAY 0.744681 (50 2100);
PAINT MONO (50 2100);
DISPLAY INVISIBLE (50 2100);
FORCEPROP 1 LAST BODY_TYPE PLUMBING
J 0
(5 2057);
DISPLAY 0.340426 (5 2057);
PAINT GREEN (5 2057);
DISPLAY INVISIBLE (5 2057);
FORCEPROP 1 LAST PATH I29
J 0
(125 2100);
DISPLAY 0.872340 (125 2100);
PAINT AQUA (125 2100);
DISPLAY INVISIBLE (125 2100);
FORCEPROP 1 LAST VOLTAGE 0.0V
J 0
(5 2057);
DISPLAY 0.340426 (5 2057);
PAINT SKYBLUE (5 2057);
DISPLAY INVISIBLE (5 2057);
FORCEPROP 1 LAST HDL_POWER GND
J 0
(50 2250);
DISPLAY 0.893617 (50 2250);
PAINT GREEN (50 2250);
DISPLAY INVISIBLE (50 2250);
FORCEADD PVDDQ_ABC..1
(-1425 2775);
FORCEPROP 3 LASTPIN (-1425 2725) SIG_NAME PVDDQ_ABC\g
J 0
(-1415 2735);
DISPLAY 0.659574 (-1415 2735);
PAINT MONO (-1415 2735);
DISPLAY INVISIBLE (-1415 2735);
FORCEPROP 1 LAST VOLTAGE 1.2V
J 0
(-1470 2732);
DISPLAY 0.340426 (-1470 2732);
PAINT SKYBLUE (-1470 2732);
DISPLAY INVISIBLE (-1470 2732);
FORCEPROP 1 LAST HDL_POWER PVDDQ_ABC
J 1
(-1425 2825);
DISPLAY 0.872340 (-1425 2825);
PAINT GREEN (-1425 2825);
DISPLAY INVISIBLE (-1425 2825);
FORCEPROP 1 LAST PATH I31
J 0
(-1375 2800);
DISPLAY 0.872340 (-1375 2800);
PAINT AQUA (-1375 2800);
DISPLAY INVISIBLE (-1375 2800);
FORCEPROP 1 LAST BODY_TYPE PLUMBING
J 0
(-1470 2732);
DISPLAY 0.340426 (-1470 2732);
PAINT GREEN (-1470 2732);
DISPLAY INVISIBLE (-1470 2732);
FORCEPROP 2 LAST CDS_LIB mstr_symbols
J 0
(-1425 2775);
PAINT ORANGE (-1425 2775);
DISPLAY INVISIBLE (-1425 2775);
FORCEADD RES..2
R 1
(-775 1525);
FORCEPROP 1 LAST WATTAGE 1/16W
J 0
(-750 1465);
DISPLAY 0.617021 (-750 1465);
PAINT SKYBLUE (-750 1465);
FORCEPROP 1 LAST TOLERANCE 5%
J 0
(-925 1470);
DISPLAY 0.617021 (-925 1470);
PAINT SKYBLUE (-925 1470);
FORCEPROP 1 LAST VALUE 0.0
J 0
(-850 1470);
DISPLAY 0.617021 (-850 1470);
PAINT SKYBLUE (-850 1470);
FORCEPROP 1 LAST PART_NUMBER G21497-005
J 0
(-875 1415);
DISPLAY 0.617021 (-875 1415);
PAINT BLUE (-875 1415);
FORCEPROP 1 LASTPIN (-675 1525) $PN 2
R 1
J 0
(-685 1530);
DISPLAY 0.617021 (-685 1530);
PAINT WHITE (-685 1530);
FORCEPROP 1 LASTPIN (-875 1525) $PN 1
R 1
J 0
(-837 1530);
DISPLAY 0.617021 (-837 1530);
PAINT WHITE (-837 1530);
FORCEPROP 1 LAST LOCATION R6U5
J 0
(-800 1570);
DISPLAY 0.617021 (-800 1570);
PAINT AQUA (-800 1570);
FORCEPROP 1 LAST PACK_TYPE 0402
J 0
(-550 1465);
DISPLAY 0.617021 (-550 1465);
PAINT SKYBLUE (-550 1465);
FORCEPROP 2 LAST CDS_LIB mstr_discrete
R 1
J 0
(-775 1525);
PAINT ORANGE (-775 1525);
DISPLAY INVISIBLE (-775 1525);
FORCEPROP 1 LAST MATERIAL CHIP
J 0
(-850 1290);
PAINT SKYBLUE (-850 1290);
DISPLAY INVISIBLE (-850 1290);
FORCEPROP 2 LAST ROOM VTT_ABC_PWR_VR
J 0
(-800 1625);
DISPLAY 1.021277 (-800 1625);
PAINT ORANGE (-800 1625);
DISPLAY INVISIBLE (-800 1625);
FORCEPROP 1 LAST PATH I32
R 1
J 0
(-950 1575);
DISPLAY 0.978723 (-950 1575);
PAINT WHITE (-950 1575);
DISPLAY INVISIBLE (-950 1575);
FORCEPROP 0 LAST NO_XNET_CONNECTION 1
J 0
(-800 1600);
PAINT MONO (-800 1600);
DISPLAY INVISIBLE (-800 1600);
FORCEPROP 2 LAST CDS_LOCATION R6U5
J 0
(-800 1570);
DISPLAY 0.617021 (-800 1570);
PAINT AQUA (-800 1570);
DISPLAY INVISIBLE (-800 1570);
FORCEPROP 2 LAST SEC 1
J 0
(-794 1615);
DISPLAY 0.680851 (-794 1615);
PAINT MONO (-794 1615);
DISPLAY INVISIBLE (-794 1615);
FORCEPROP 2 LAST BOM_COST MEM_VRD_VTT_ABC
J 0
(-800 1675);
DISPLAY 1.021277 (-800 1675);
PAINT ORANGE (-800 1675);
DISPLAY INVISIBLE (-800 1675);
FORCEPROP 2 LAST SEC_TYPE 0402
J 0
(-794 1615);
DISPLAY 1.021277 (-794 1615);
PAINT ORANGE (-794 1615);
DISPLAY INVISIBLE (-794 1615);
FORCEADD CAP..1
(2375 825);
FORCEPROP 1 LASTPIN (2375 725) $PN 2
J 0
(2385 705);
DISPLAY 0.617021 (2385 705);
PAINT WHITE (2385 705);
FORCEPROP 1 LAST PACK_TYPE 0402
J 0
(2425 725);
DISPLAY 0.617021 (2425 725);
PAINT SKYBLUE (2425 725);
FORCEPROP 1 LASTPIN (2375 925) $PN 1
J 0
(2385 905);
DISPLAY 0.617021 (2385 905);
PAINT WHITE (2385 905);
FORCEPROP 1 LAST TOLERANCE 10%
J 0
(2425 825);
DISPLAY 0.617021 (2425 825);
PAINT SKYBLUE (2425 825);
FORCEPROP 1 LAST MATERIAL X6S
J 0
(2550 825);
DISPLAY 0.617021 (2550 825);
PAINT SKYBLUE (2550 825);
FORCEPROP 1 LAST VALUE 1.0UF
J 0
(2425 875);
DISPLAY 0.617021 (2425 875);
PAINT SKYBLUE (2425 875);
FORCEPROP 1 LAST PART_NUMBER D97712-011
J 0
(2425 775);
DISPLAY 0.617021 (2425 775);
PAINT BLUE (2425 775);
FORCEPROP 1 LAST LOCATION C4G16
J 0
(2425 925);
DISPLAY 0.617021 (2425 925);
PAINT AQUA (2425 925);
FORCEPROP 1 LAST VOLTAGE 16V
J 0
(2575 875);
DISPLAY 0.617021 (2575 875);
PAINT SKYBLUE (2575 875);
FORCEPROP 2 LAST CDS_LIB mstr_discrete
J 0
(2375 825);
PAINT ORANGE (2375 825);
DISPLAY INVISIBLE (2375 825);
FORCEPROP 2 LAST CDS_LOCATION C4G16
J 0
(2425 925);
DISPLAY 0.617021 (2425 925);
PAINT AQUA (2425 925);
DISPLAY INVISIBLE (2425 925);
FORCEPROP 1 LAST PATH I34
J 0
(2425 975);
DISPLAY 0.978723 (2425 975);
PAINT WHITE (2425 975);
DISPLAY INVISIBLE (2425 975);
FORCEPROP 2 LAST ROOM VTT_ABC_PWR_VR
J 0
(2425 975);
DISPLAY 1.021277 (2425 975);
PAINT ORANGE (2425 975);
DISPLAY INVISIBLE (2425 975);
FORCEPROP 2 LAST SEC 1
J 0
(2431 1040);
DISPLAY 0.680851 (2431 1040);
PAINT MONO (2431 1040);
DISPLAY INVISIBLE (2431 1040);
FORCEPROP 2 LAST BOM_COST MEM_VRD_VTT_ABC
J 0
(2425 1025);
DISPLAY 1.021277 (2425 1025);
PAINT ORANGE (2425 1025);
DISPLAY INVISIBLE (2425 1025);
FORCEPROP 2 LAST SEC_TYPE 0402
J 0
(2431 1040);
DISPLAY 1.021277 (2431 1040);
PAINT ORANGE (2431 1040);
DISPLAY INVISIBLE (2431 1040);
FORCEADD GND..1
(2000 575);
FORCEPROP 3 LASTPIN (2000 625) SIG_NAME GND\g
J 0
(2010 635);
DISPLAY 0.659574 (2010 635);
PAINT MONO (2010 635);
DISPLAY INVISIBLE (2010 635);
FORCEPROP 2 LAST CDS_LIB mstr_symbols
J 0
(2000 575);
PAINT ORANGE (2000 575);
DISPLAY INVISIBLE (2000 575);
FORCEPROP 1 LAST BODY_TYPE PLUMBING
J 0
(1955 532);
DISPLAY 0.340426 (1955 532);
PAINT GREEN (1955 532);
DISPLAY INVISIBLE (1955 532);
FORCEPROP 1 LAST VOLTAGE 0.0V
J 0
(1955 532);
DISPLAY 0.340426 (1955 532);
PAINT SKYBLUE (1955 532);
DISPLAY INVISIBLE (1955 532);
FORCEPROP 1 LAST HDL_POWER GND
J 0
(2000 725);
DISPLAY 0.872340 (2000 725);
PAINT GREEN (2000 725);
DISPLAY INVISIBLE (2000 725);
FORCEPROP 1 LAST SIZE 1B
J 0
(2075 525);
DISPLAY 0.872340 (2075 525);
PAINT AQUA (2075 525);
DISPLAY INVISIBLE (2075 525);
FORCEPROP 1 LAST PATH I35
J 0
(2075 575);
DISPLAY 0.872340 (2075 575);
PAINT AQUA (2075 575);
DISPLAY INVISIBLE (2075 575);
FORCEADD GND..1
(2375 575);
FORCEPROP 3 LASTPIN (2375 625) SIG_NAME GND\g
J 0
(2385 635);
DISPLAY 0.659574 (2385 635);
PAINT MONO (2385 635);
DISPLAY INVISIBLE (2385 635);
FORCEPROP 2 LAST CDS_LIB mstr_symbols
J 0
(2375 575);
PAINT ORANGE (2375 575);
DISPLAY INVISIBLE (2375 575);
FORCEPROP 1 LAST BODY_TYPE PLUMBING
J 0
(2330 532);
DISPLAY 0.340426 (2330 532);
PAINT GREEN (2330 532);
DISPLAY INVISIBLE (2330 532);
FORCEPROP 1 LAST VOLTAGE 0.0V
J 0
(2330 532);
DISPLAY 0.340426 (2330 532);
PAINT SKYBLUE (2330 532);
DISPLAY INVISIBLE (2330 532);
FORCEPROP 1 LAST HDL_POWER GND
J 0
(2375 725);
DISPLAY 0.872340 (2375 725);
PAINT GREEN (2375 725);
DISPLAY INVISIBLE (2375 725);
FORCEPROP 1 LAST PATH I36
J 0
(2450 575);
DISPLAY 0.872340 (2450 575);
PAINT AQUA (2450 575);
DISPLAY INVISIBLE (2450 575);
FORCEPROP 1 LAST SIZE 1B
J 0
(2450 525);
DISPLAY 0.872340 (2450 525);
PAINT AQUA (2450 525);
DISPLAY INVISIBLE (2450 525);
FORCEADD RES..2
R 2
(-325 650);
FORCEPROP 1 LAST PART_NUMBER G21796-021
J 2
(-365 525);
DISPLAY 0.617021 (-365 525);
PAINT BLUE (-365 525);
FORCEPROP 1 LAST LOCATION R6U15
J 2
(-370 775);
DISPLAY 0.617021 (-370 775);
PAINT AQUA (-370 775);
FORCEPROP 1 LAST PACK_TYPE 0402
J 2
(-365 475);
DISPLAY 0.617021 (-365 475);
PAINT SKYBLUE (-365 475);
FORCEPROP 1 LAST WATTAGE 1/16W
J 2
(-365 625);
DISPLAY 0.617021 (-365 625);
PAINT SKYBLUE (-365 625);
FORCEPROP 1 LAST TOLERANCE 1%
J 2
(-370 675);
DISPLAY 0.617021 (-370 675);
PAINT SKYBLUE (-370 675);
FORCEPROP 1 LAST VALUE 1.0M
J 2
(-370 725);
DISPLAY 0.617021 (-370 725);
PAINT SKYBLUE (-370 725);
FORCEPROP 1 LAST MATERIAL EMPTY
J 2
(-365 575);
DISPLAY 0.617021 (-365 575);
PAINT RED (-365 575);
FORCEPROP 1 LASTPIN (-325 550) $PN 2
J 2
(-330 560);
DISPLAY 0.617021 (-330 560);
PAINT WHITE (-330 560);
FORCEPROP 1 LASTPIN (-325 750) $PN 1
J 2
(-330 712);
DISPLAY 0.617021 (-330 712);
PAINT WHITE (-330 712);
FORCEPROP 2 LAST CDS_LIB mstr_discrete
J 0
(-325 650);
PAINT ORANGE (-325 650);
DISPLAY INVISIBLE (-325 650);
FORCEPROP 2 LAST SEC_TYPE 0402
J 0
(-354 880);
DISPLAY 1.021277 (-354 880);
PAINT ORANGE (-354 880);
DISPLAY INVISIBLE (-354 880);
FORCEPROP 2 LAST BOM_COST MEM_VRD_VTT_ABC
J 0
(-360 865);
DISPLAY 1.021277 (-360 865);
PAINT ORANGE (-360 865);
DISPLAY INVISIBLE (-360 865);
FORCEPROP 2 LAST SEC 1
J 0
(-354 880);
DISPLAY 0.680851 (-354 880);
PAINT MONO (-354 880);
DISPLAY INVISIBLE (-354 880);
FORCEPROP 2 LAST CDS_LOCATION R6U15
J 2
(-370 775);
DISPLAY 0.617021 (-370 775);
PAINT AQUA (-370 775);
DISPLAY INVISIBLE (-370 775);
FORCEPROP 1 LAST PATH I37
J 2
(-375 825);
DISPLAY 0.978723 (-375 825);
PAINT WHITE (-375 825);
DISPLAY INVISIBLE (-375 825);
FORCEPROP 2 LAST ROOM VTT_ABC_PWR_VR
J 0
(-360 815);
DISPLAY 1.021277 (-360 815);
PAINT ORANGE (-360 815);
DISPLAY INVISIBLE (-360 815);
FORCEADD RES..1
(-525 125);
FORCEPROP 1 LAST MATERIAL CHIP
J 0
(-825 -50);
DISPLAY 0.617021 (-825 -50);
PAINT SKYBLUE (-825 -50);
FORCEPROP 1 LAST PACK_TYPE 0402
J 0
(-600 -50);
DISPLAY 0.617021 (-600 -50);
PAINT SKYBLUE (-600 -50);
FORCEPROP 1 LAST WATTAGE 1/16W
J 2
(-675 25);
DISPLAY 0.617021 (-675 25);
PAINT SKYBLUE (-675 25);
FORCEPROP 1 LAST VALUE 0.0
J 2
(-550 25);
DISPLAY 0.617021 (-550 25);
PAINT SKYBLUE (-550 25);
FORCEPROP 1 LASTPIN (-625 125) $PN 1
J 0
(-613 137);
DISPLAY 0.617021 (-613 137);
PAINT WHITE (-613 137);
FORCEPROP 1 LAST TOLERANCE 5%
J 0
(-525 25);
DISPLAY 0.617021 (-525 25);
PAINT SKYBLUE (-525 25);
FORCEPROP 1 LAST PART_NUMBER G21497-005
J 0
(-700 75);
DISPLAY 0.617021 (-700 75);
PAINT BLUE (-700 75);
FORCEPROP 1 LAST LOCATION R4G23
J 0
(-575 175);
DISPLAY 0.617021 (-575 175);
PAINT AQUA (-575 175);
FORCEPROP 1 LASTPIN (-425 125) $PN 2
J 0
(-463 137);
DISPLAY 0.617021 (-463 137);
PAINT WHITE (-463 137);
FORCEPROP 2 LAST CDS_LOCATION R4G23
J 0
(-575 175);
DISPLAY 0.617021 (-575 175);
PAINT AQUA (-575 175);
DISPLAY INVISIBLE (-575 175);
FORCEPROP 2 LAST CDS_LIB mstr_discrete
J 0
(-525 125);
PAINT ORANGE (-525 125);
DISPLAY INVISIBLE (-525 125);
FORCEPROP 2 LAST ROOM VTT_ABC_PWR_VR
J 0
(-555 280);
DISPLAY 1.021277 (-555 280);
PAINT ORANGE (-555 280);
DISPLAY INVISIBLE (-555 280);
FORCEPROP 1 LAST PATH I38
J 0
(-575 275);
DISPLAY 0.978723 (-575 275);
PAINT WHITE (-575 275);
DISPLAY INVISIBLE (-575 275);
FORCEPROP 2 LAST SEC 1
J 0
(-575 325);
DISPLAY 0.680851 (-575 325);
PAINT MONO (-575 325);
DISPLAY INVISIBLE (-575 325);
FORCEPROP 2 LAST SEC_TYPE 0402
J 0
(-575 325);
DISPLAY 1.021277 (-575 325);
PAINT ORANGE (-575 325);
DISPLAY INVISIBLE (-575 325);
FORCEPROP 2 LAST BOM_COST MEM_VRD_VTT_ABC
J 0
(-555 330);
DISPLAY 1.021277 (-555 330);
PAINT ORANGE (-555 330);
DISPLAY INVISIBLE (-555 330);
FORCEADD CAP..1
R 2
(-375 -400);
FORCEPROP 1 LAST VOLTAGE 50V
J 2
(-425 -400);
DISPLAY 0.617021 (-425 -400);
PAINT SKYBLUE (-425 -400);
FORCEPROP 1 LAST PACK_TYPE 0402LF
J 2
(-425 -450);
DISPLAY 0.617021 (-425 -450);
PAINT SKYBLUE (-425 -450);
FORCEPROP 1 LAST TOLERANCE 10%
J 2
(-425 -450);
DISPLAY 0.617021 (-425 -450);
PAINT SKYBLUE (-425 -450);
FORCEPROP 1 LAST VALUE 1000PF
J 2
(-425 -350);
DISPLAY 0.617021 (-425 -350);
PAINT SKYBLUE (-425 -350);
FORCEPROP 1 LAST LOCATION C4G23
J 2
(-425 -300);
DISPLAY 0.617021 (-425 -300);
PAINT AQUA (-425 -300);
FORCEPROP 1 LAST MATERIAL EMPTY
J 2
(-425 -500);
DISPLAY 0.617021 (-425 -500);
PAINT RED (-425 -500);
FORCEPROP 1 LASTPIN (-375 -500) $PN 2
J 2
(-385 -520);
DISPLAY 0.617021 (-385 -520);
PAINT WHITE (-385 -520);
FORCEPROP 1 LASTPIN (-375 -300) $PN 1
J 2
(-385 -320);
DISPLAY 0.617021 (-385 -320);
PAINT WHITE (-385 -320);
FORCEPROP 1 LAST PART_NUMBER A36096-046
J 2
(-425 -550);
DISPLAY 0.659574 (-425 -550);
PAINT BLUE (-425 -550);
DISPLAY INVISIBLE (-425 -550);
FORCEPROP 2 LAST CDS_LOCATION C4G23
J 2
(-425 -300);
DISPLAY 0.617021 (-425 -300);
PAINT AQUA (-425 -300);
DISPLAY INVISIBLE (-425 -300);
FORCEPROP 2 LAST CDS_LIB mstr_discrete
J 0
(-375 -400);
PAINT ORANGE (-375 -400);
DISPLAY INVISIBLE (-375 -400);
FORCEPROP 2 LAST BOM_COST MEM_VRD_VTT_ABC
J 0
(-410 -195);
DISPLAY 1.021277 (-410 -195);
PAINT ORANGE (-410 -195);
DISPLAY INVISIBLE (-410 -195);
FORCEPROP 2 LAST SEC_TYPE 0402LF
J 0
(-404 -180);
DISPLAY 1.021277 (-404 -180);
PAINT ORANGE (-404 -180);
DISPLAY INVISIBLE (-404 -180);
FORCEPROP 2 LAST SEC 1
J 0
(-404 -180);
DISPLAY 0.680851 (-404 -180);
PAINT MONO (-404 -180);
DISPLAY INVISIBLE (-404 -180);
FORCEPROP 1 LAST PATH I39
J 2
(-425 -250);
DISPLAY 0.978723 (-425 -250);
PAINT WHITE (-425 -250);
DISPLAY INVISIBLE (-425 -250);
FORCEPROP 2 LAST ROOM VTT_ABC_PWR_VR
J 0
(-410 -245);
DISPLAY 1.021277 (-410 -245);
PAINT ORANGE (-410 -245);
DISPLAY INVISIBLE (-410 -245);
FORCEADD GND..1
(-375 -625);
FORCEPROP 3 LASTPIN (-375 -575) SIG_NAME GND\g
J 0
(-365 -565);
DISPLAY 0.659574 (-365 -565);
PAINT MONO (-365 -565);
DISPLAY INVISIBLE (-365 -565);
FORCEPROP 2 LAST CDS_LIB mstr_symbols
J 0
(-375 -625);
PAINT MONO (-375 -625);
DISPLAY INVISIBLE (-375 -625);
FORCEPROP 1 LAST SIZE 1B
J 0
(-300 -675);
DISPLAY 0.893617 (-300 -675);
PAINT GREEN (-300 -675);
DISPLAY INVISIBLE (-300 -675);
FORCEPROP 1 LAST BODY_TYPE PLUMBING
J 0
(-420 -668);
DISPLAY 0.340426 (-420 -668);
PAINT GREEN (-420 -668);
DISPLAY INVISIBLE (-420 -668);
FORCEPROP 1 LAST PATH I40
J 0
(-300 -625);
DISPLAY 0.872340 (-300 -625);
PAINT AQUA (-300 -625);
DISPLAY INVISIBLE (-300 -625);
FORCEPROP 1 LAST VOLTAGE 0.0V
J 0
(-420 -668);
DISPLAY 0.340426 (-420 -668);
PAINT SKYBLUE (-420 -668);
DISPLAY INVISIBLE (-420 -668);
FORCEPROP 1 LAST HDL_POWER GND
J 0
(-375 -475);
DISPLAY 0.893617 (-375 -475);
PAINT GREEN (-375 -475);
DISPLAY INVISIBLE (-375 -475);
FORCEADD OFFPAGE..1
(-1400 125);
FORCEPROP 2 LAST $XR0 215 
J 0
(-1652 125);
DISPLAY 0.638298 (-1652 125);
PAINT MONO (-1652 125);
FORCEPROP 1 LAST OFFPAGE TRUE
J 0
(-1075 0);
DISPLAY 0.872340 (-1075 0);
PAINT GREEN (-1075 0);
DISPLAY INVISIBLE (-1075 0);
FORCEPROP 2 LAST PATH I41
J 0
(-1669 170);
DISPLAY 1.021277 (-1669 170);
PAINT ORANGE (-1669 170);
DISPLAY INVISIBLE (-1669 170);
FORCEPROP 1 LAST COMMENT_BODY TRUE
J 0
(-1275 25);
DISPLAY 0.872340 (-1275 25);
PAINT GREEN (-1275 25);
DISPLAY INVISIBLE (-1275 25);
FORCEPROP 2 LAST CDS_LIB mstr_standard
J 0
(-1400 125);
DISPLAY 0.744681 (-1400 125);
PAINT MONO (-1400 125);
DISPLAY INVISIBLE (-1400 125);
FORCEADD P3V3..1
(-550 2050);
FORCEPROP 3 LASTPIN (-550 2000) SIG_NAME P3V3\g
J 0
(-540 2010);
DISPLAY 0.659574 (-540 2010);
PAINT MONO (-540 2010);
DISPLAY INVISIBLE (-540 2010);
FORCEPROP 1 LAST HDL_POWER P3V3
J 0
(-875 1925);
DISPLAY 0.872340 (-875 1925);
PAINT ORANGE (-875 1925);
DISPLAY INVISIBLE (-875 1925);
FORCEPROP 1 LAST VOLTAGE 3.3V
J 0
(-595 2007);
DISPLAY 0.340426 (-595 2007);
PAINT SKYBLUE (-595 2007);
DISPLAY INVISIBLE (-595 2007);
FORCEPROP 1 LAST BODY_TYPE PLUMBING
J 0
(-595 2007);
DISPLAY 0.340426 (-595 2007);
PAINT GREEN (-595 2007);
DISPLAY INVISIBLE (-595 2007);
FORCEPROP 1 LAST PATH I43
J 0
(-505 2052);
DISPLAY 0.340426 (-505 2052);
PAINT GREEN (-505 2052);
DISPLAY INVISIBLE (-505 2052);
FORCEPROP 1 LAST SIZE 1B
J 0
(-505 2072);
DISPLAY 0.340426 (-505 2072);
PAINT GREEN (-505 2072);
DISPLAY INVISIBLE (-505 2072);
FORCEPROP 2 LAST CDS_LIB mstr_symbols
J 0
(-550 2050);
PAINT ORANGE (-550 2050);
DISPLAY INVISIBLE (-550 2050);
FORCEADD RES..2
(3500 2025);
FORCEPROP 1 LASTPIN (3500 1925) $PN 2
J 0
(3505 1935);
DISPLAY 0.617021 (3505 1935);
PAINT ORANGE (3505 1935);
FORCEPROP 1 LAST WATTAGE 1/16W
J 0
(3540 2000);
DISPLAY 0.617021 (3540 2000);
PAINT SKYBLUE (3540 2000);
FORCEPROP 1 LAST MATERIAL CHIP
J 0
(3540 1950);
DISPLAY 0.617021 (3540 1950);
PAINT SKYBLUE (3540 1950);
FORCEPROP 1 LAST PACK_TYPE 0402
J 0
(3540 1850);
DISPLAY 0.617021 (3540 1850);
PAINT SKYBLUE (3540 1850);
FORCEPROP 1 LAST PART_NUMBER G21796-016
J 0
(3540 1900);
DISPLAY 0.617021 (3540 1900);
PAINT BLUE (3540 1900);
FORCEPROP 1 LASTPIN (3500 2125) $PN 1
J 0
(3505 2087);
DISPLAY 0.617021 (3505 2087);
PAINT ORANGE (3505 2087);
FORCEPROP 1 LAST TOLERANCE 1%
J 0
(3545 2050);
DISPLAY 0.617021 (3545 2050);
PAINT SKYBLUE (3545 2050);
FORCEPROP 1 LAST VALUE 10.0K
J 0
(3545 2100);
DISPLAY 0.617021 (3545 2100);
PAINT SKYBLUE (3545 2100);
FORCEPROP 1 LAST LOCATION R4G18
J 0
(3545 2150);
DISPLAY 0.617021 (3545 2150);
PAINT AQUA (3545 2150);
FORCEPROP 2 LAST CDS_LIB mstr_discrete
J 0
(3500 2025);
PAINT ORANGE (3500 2025);
DISPLAY INVISIBLE (3500 2025);
FORCEPROP 2 LAST CDS_LOCATION R4G18
J 0
(3545 2150);
DISPLAY 0.617021 (3545 2150);
PAINT AQUA (3545 2150);
DISPLAY INVISIBLE (3545 2150);
FORCEPROP 0 LAST ROOM VTT_ABC_PWR_VR
J 0
(3545 2244);
DISPLAY 1.021277 (3545 2244);
PAINT ORANGE (3545 2244);
DISPLAY INVISIBLE (3545 2244);
FORCEPROP 2 LAST SEC 1
J 0
(3550 2250);
PAINT MONO (3550 2250);
DISPLAY INVISIBLE (3550 2250);
FORCEPROP 2 LAST SEC_TYPE 0402
J 0
(3550 2250);
DISPLAY 1.021277 (3550 2250);
PAINT ORANGE (3550 2250);
DISPLAY INVISIBLE (3550 2250);
FORCEPROP 0 LAST BOM_COST MEM_VRD_VTT_ABC
J 0
(3545 2244);
DISPLAY 1.021277 (3545 2244);
PAINT ORANGE (3545 2244);
DISPLAY INVISIBLE (3545 2244);
FORCEPROP 1 LAST PATH I45
J 0
(3550 2200);
DISPLAY 0.978723 (3550 2200);
PAINT WHITE (3550 2200);
DISPLAY INVISIBLE (3550 2200);
FORCEADD P3V3..1
(3500 2275);
FORCEPROP 3 LASTPIN (3500 2225) SIG_NAME P3V3\g
J 0
(3510 2235);
DISPLAY 0.659574 (3510 2235);
PAINT MONO (3510 2235);
DISPLAY INVISIBLE (3510 2235);
FORCEPROP 1 LAST HDL_POWER P3V3
J 0
(3175 2150);
DISPLAY 0.872340 (3175 2150);
PAINT ORANGE (3175 2150);
DISPLAY INVISIBLE (3175 2150);
FORCEPROP 1 LAST VOLTAGE 3.3V
J 0
(3455 2232);
DISPLAY 0.340426 (3455 2232);
PAINT SKYBLUE (3455 2232);
DISPLAY INVISIBLE (3455 2232);
FORCEPROP 1 LAST BODY_TYPE PLUMBING
J 0
(3455 2232);
DISPLAY 0.340426 (3455 2232);
PAINT GREEN (3455 2232);
DISPLAY INVISIBLE (3455 2232);
FORCEPROP 1 LAST PATH I46
J 0
(3545 2277);
DISPLAY 0.340426 (3545 2277);
PAINT GREEN (3545 2277);
DISPLAY INVISIBLE (3545 2277);
FORCEPROP 1 LAST SIZE 1B
J 0
(3545 2297);
DISPLAY 0.340426 (3545 2297);
PAINT GREEN (3545 2297);
DISPLAY INVISIBLE (3545 2297);
FORCEPROP 2 LAST CDS_LIB mstr_symbols
J 0
(3500 2275);
PAINT ORANGE (3500 2275);
DISPLAY INVISIBLE (3500 2275);
FORCEADD GND..1
(325 775);
FORCEPROP 3 LASTPIN (325 825) SIG_NAME GND\g
J 0
(335 835);
DISPLAY 0.659574 (335 835);
PAINT MONO (335 835);
DISPLAY INVISIBLE (335 835);
FORCEPROP 1 LAST SIZE 1B
J 0
(400 725);
DISPLAY 0.872340 (400 725);
PAINT AQUA (400 725);
DISPLAY INVISIBLE (400 725);
FORCEPROP 1 LAST BODY_TYPE PLUMBING
J 0
(280 732);
DISPLAY 0.340426 (280 732);
PAINT GREEN (280 732);
DISPLAY INVISIBLE (280 732);
FORCEPROP 1 LAST VOLTAGE 0.0V
J 0
(280 732);
DISPLAY 0.340426 (280 732);
PAINT SKYBLUE (280 732);
DISPLAY INVISIBLE (280 732);
FORCEPROP 2 LAST CDS_LIB mstr_symbols
J 0
(325 775);
PAINT ORANGE (325 775);
DISPLAY INVISIBLE (325 775);
FORCEPROP 1 LAST HDL_POWER GND
J 0
(325 925);
DISPLAY 0.872340 (325 925);
PAINT GREEN (325 925);
DISPLAY INVISIBLE (325 925);
FORCEPROP 1 LAST PATH I48
J 0
(400 775);
DISPLAY 0.872340 (400 775);
PAINT AQUA (400 775);
DISPLAY INVISIBLE (400 775);
FORCEADD CAP..1
(325 1000);
FORCEPROP 1 LASTPIN (325 900) $PN 2
J 0
(335 880);
DISPLAY 0.617021 (335 880);
PAINT ORANGE (335 880);
FORCEPROP 1 LAST TOLERANCE 10%
J 0
(375 950);
DISPLAY 0.617021 (375 950);
PAINT SKYBLUE (375 950);
FORCEPROP 1 LAST PACK_TYPE 0603
J 0
(375 800);
DISPLAY 0.617021 (375 800);
PAINT SKYBLUE (375 800);
FORCEPROP 1 LAST MATERIAL X6S
J 0
(375 900);
DISPLAY 0.617021 (375 900);
PAINT SKYBLUE (375 900);
FORCEPROP 1 LAST PART_NUMBER E15431-003
J 0
(375 850);
DISPLAY 0.617021 (375 850);
PAINT BLUE (375 850);
FORCEPROP 1 LAST VOLTAGE 6.3V
J 0
(375 1000);
DISPLAY 0.617021 (375 1000);
PAINT SKYBLUE (375 1000);
FORCEPROP 1 LASTPIN (325 1100) $PN 1
J 0
(335 1080);
DISPLAY 0.617021 (335 1080);
PAINT ORANGE (335 1080);
FORCEPROP 1 LAST VALUE 4.7UF
J 0
(375 1050);
DISPLAY 0.617021 (375 1050);
PAINT SKYBLUE (375 1050);
FORCEPROP 1 LAST LOCATION C6U12
J 0
(375 1100);
DISPLAY 0.617021 (375 1100);
PAINT AQUA (375 1100);
FORCEPROP 2 LAST CDS_LIB mstr_discrete
J 0
(325 1000);
PAINT ORANGE (325 1000);
DISPLAY INVISIBLE (325 1000);
FORCEPROP 0 LAST ROOM VTT_ABC_PWR_VR
J 0
(375 1200);
DISPLAY 1.021277 (375 1200);
PAINT ORANGE (375 1200);
DISPLAY INVISIBLE (375 1200);
FORCEPROP 2 LAST SEC_TYPE 0603
J 0
(375 1200);
DISPLAY 1.021277 (375 1200);
PAINT ORANGE (375 1200);
DISPLAY INVISIBLE (375 1200);
FORCEPROP 2 LAST SEC 1
J 0
(375 1200);
DISPLAY 0.680851 (375 1200);
PAINT MONO (375 1200);
DISPLAY INVISIBLE (375 1200);
FORCEPROP 1 LAST PATH I49
J 0
(375 1150);
DISPLAY 0.978723 (375 1150);
PAINT WHITE (375 1150);
DISPLAY INVISIBLE (375 1150);
FORCEPROP 2 LAST CDS_LOCATION C6U12
J 0
(375 1100);
DISPLAY 0.617021 (375 1100);
PAINT AQUA (375 1100);
DISPLAY INVISIBLE (375 1100);
FORCEADD CAP_A..1
(3600 3450);
FORCEPROP 1 LAST PACK_TYPE 0603V
J 0
(3650 3250);
DISPLAY 0.617021 (3650 3250);
PAINT SKYBLUE (3650 3250);
FORCEPROP 1 LAST LOCATION C5U12
J 0
(3650 3550);
DISPLAY 0.617021 (3650 3550);
PAINT AQUA (3650 3550);
FORCEPROP 1 LAST VALUE 47UF
J 0
(3650 3500);
DISPLAY 0.617021 (3650 3500);
PAINT SKYBLUE (3650 3500);
FORCEPROP 1 LAST TOLERANCE 20%
J 0
(3650 3400);
DISPLAY 0.617021 (3650 3400);
PAINT SKYBLUE (3650 3400);
FORCEPROP 1 LAST VOLTAGE 4V
J 0
(3650 3450);
DISPLAY 0.617021 (3650 3450);
PAINT SKYBLUE (3650 3450);
FORCEPROP 1 LAST MATERIAL X5R
J 0
(3650 3350);
DISPLAY 0.617021 (3650 3350);
PAINT SKYBLUE (3650 3350);
FORCEPROP 1 LASTPIN (3600 3350) $PN 2
J 0
(3610 3330);
DISPLAY 0.617021 (3610 3330);
PAINT ORANGE (3610 3330);
FORCEPROP 1 LASTPIN (3600 3550) $PN 1
J 0
(3610 3530);
DISPLAY 0.617021 (3610 3530);
PAINT ORANGE (3610 3530);
FORCEPROP 1 LAST PART_NUMBER 602433-106
J 0
(3650 3300);
DISPLAY 0.617021 (3650 3300);
PAINT BLUE (3650 3300);
FORCEPROP 2 LAST CDS_LIB dev_discrete
J 0
(3600 3450);
PAINT ORANGE (3600 3450);
DISPLAY INVISIBLE (3600 3450);
FORCEPROP 2 LAST CDS_LOCATION C5U12
J 0
(3650 3550);
DISPLAY 0.617021 (3650 3550);
PAINT AQUA (3650 3550);
DISPLAY INVISIBLE (3650 3550);
FORCEPROP 2 LAST CDS_SEC 1
J 0
(3650 3600);
PAINT ORANGE (3650 3600);
DISPLAY INVISIBLE (3650 3600);
FORCEPROP 2 LAST SEC_TYPE 0603V
J 0
(3650 3650);
DISPLAY 1.021277 (3650 3650);
PAINT ORANGE (3650 3650);
DISPLAY INVISIBLE (3650 3650);
FORCEPROP 2 LAST SEC 1
J 0
(3650 3650);
DISPLAY 0.680851 (3650 3650);
PAINT MONO (3650 3650);
DISPLAY INVISIBLE (3650 3650);
FORCEPROP 1 LAST PATH I50
J 0
(3650 3600);
DISPLAY 0.978723 (3650 3600);
PAINT WHITE (3650 3600);
DISPLAY INVISIBLE (3650 3600);
FORCEADD CAP_A..1
(3950 3450);
FORCEPROP 1 LAST TOLERANCE 20%
J 0
(4000 3400);
DISPLAY 0.617021 (4000 3400);
PAINT SKYBLUE (4000 3400);
FORCEPROP 1 LAST VOLTAGE 4V
J 0
(4000 3450);
DISPLAY 0.617021 (4000 3450);
PAINT SKYBLUE (4000 3450);
FORCEPROP 1 LAST MATERIAL X5R
J 0
(4000 3350);
DISPLAY 0.617021 (4000 3350);
PAINT SKYBLUE (4000 3350);
FORCEPROP 1 LASTPIN (3950 3350) $PN 2
J 0
(3960 3330);
DISPLAY 0.617021 (3960 3330);
PAINT ORANGE (3960 3330);
FORCEPROP 1 LASTPIN (3950 3550) $PN 1
J 0
(3960 3530);
DISPLAY 0.617021 (3960 3530);
PAINT ORANGE (3960 3530);
FORCEPROP 1 LAST PACK_TYPE 0603V
J 0
(4000 3250);
DISPLAY 0.617021 (4000 3250);
PAINT SKYBLUE (4000 3250);
FORCEPROP 1 LAST VALUE 47UF
J 0
(4000 3500);
DISPLAY 0.617021 (4000 3500);
PAINT SKYBLUE (4000 3500);
FORCEPROP 1 LAST PART_NUMBER 602433-106
J 0
(4000 3300);
DISPLAY 0.617021 (4000 3300);
PAINT BLUE (4000 3300);
FORCEPROP 1 LAST LOCATION C5T3
J 0
(4000 3550);
DISPLAY 0.617021 (4000 3550);
PAINT AQUA (4000 3550);
FORCEPROP 2 LAST CDS_LIB dev_discrete
J 0
(3950 3450);
PAINT ORANGE (3950 3450);
DISPLAY INVISIBLE (3950 3450);
FORCEPROP 2 LAST CDS_LOCATION C5T3
J 0
(4000 3550);
DISPLAY 0.617021 (4000 3550);
PAINT AQUA (4000 3550);
DISPLAY INVISIBLE (4000 3550);
FORCEPROP 1 LAST PATH I51
J 0
(4000 3600);
DISPLAY 0.978723 (4000 3600);
PAINT WHITE (4000 3600);
DISPLAY INVISIBLE (4000 3600);
FORCEPROP 2 LAST SEC 1
J 0
(4000 3650);
DISPLAY 0.680851 (4000 3650);
PAINT MONO (4000 3650);
DISPLAY INVISIBLE (4000 3650);
FORCEPROP 2 LAST SEC_TYPE 0603V
J 0
(4000 3650);
DISPLAY 1.021277 (4000 3650);
PAINT ORANGE (4000 3650);
DISPLAY INVISIBLE (4000 3650);
FORCEPROP 2 LAST CDS_SEC 1
J 0
(4000 3600);
PAINT ORANGE (4000 3600);
DISPLAY INVISIBLE (4000 3600);
FORCEADD CAP_A..1
(4350 3450);
FORCEPROP 1 LASTPIN (4350 3550) $PN 1
J 0
(4360 3530);
DISPLAY 0.617021 (4360 3530);
PAINT ORANGE (4360 3530);
FORCEPROP 1 LASTPIN (4350 3350) $PN 2
J 0
(4360 3330);
DISPLAY 0.617021 (4360 3330);
PAINT ORANGE (4360 3330);
FORCEPROP 1 LAST MATERIAL X5R
J 0
(4400 3350);
DISPLAY 0.617021 (4400 3350);
PAINT SKYBLUE (4400 3350);
FORCEPROP 1 LAST VOLTAGE 4V
J 0
(4400 3450);
DISPLAY 0.617021 (4400 3450);
PAINT SKYBLUE (4400 3450);
FORCEPROP 1 LAST PACK_TYPE 0603V
J 0
(4400 3250);
DISPLAY 0.617021 (4400 3250);
PAINT SKYBLUE (4400 3250);
FORCEPROP 1 LAST TOLERANCE 20%
J 0
(4400 3400);
DISPLAY 0.617021 (4400 3400);
PAINT SKYBLUE (4400 3400);
FORCEPROP 1 LAST VALUE 47UF
J 0
(4400 3500);
DISPLAY 0.617021 (4400 3500);
PAINT SKYBLUE (4400 3500);
FORCEPROP 1 LAST LOCATION C5U16
J 0
(4400 3550);
DISPLAY 0.617021 (4400 3550);
PAINT AQUA (4400 3550);
FORCEPROP 1 LAST PART_NUMBER 602433-106
J 0
(4400 3300);
DISPLAY 0.617021 (4400 3300);
PAINT BLUE (4400 3300);
FORCEPROP 2 LAST CDS_LIB dev_discrete
J 0
(4350 3450);
PAINT ORANGE (4350 3450);
DISPLAY INVISIBLE (4350 3450);
FORCEPROP 2 LAST CDS_LOCATION C5U16
J 0
(4400 3550);
DISPLAY 0.617021 (4400 3550);
PAINT AQUA (4400 3550);
DISPLAY INVISIBLE (4400 3550);
FORCEPROP 2 LAST CDS_SEC 1
J 0
(4400 3600);
PAINT ORANGE (4400 3600);
DISPLAY INVISIBLE (4400 3600);
FORCEPROP 2 LAST SEC_TYPE 0603V
J 0
(4400 3650);
DISPLAY 1.021277 (4400 3650);
PAINT ORANGE (4400 3650);
DISPLAY INVISIBLE (4400 3650);
FORCEPROP 2 LAST SEC 1
J 0
(4400 3650);
DISPLAY 0.680851 (4400 3650);
PAINT MONO (4400 3650);
DISPLAY INVISIBLE (4400 3650);
FORCEPROP 1 LAST PATH I52
J 0
(4400 3600);
DISPLAY 0.978723 (4400 3600);
PAINT WHITE (4400 3600);
DISPLAY INVISIBLE (4400 3600);
FORCEADD RES..1
(4175 1800);
FORCEPROP 1 LASTPIN (4075 1800) $PN 1
J 0
(4087 1812);
DISPLAY 0.617021 (4087 1812);
PAINT ORANGE (4087 1812);
FORCEPROP 1 LAST WATTAGE 1/16W
J 2
(4150 1650);
DISPLAY 0.617021 (4150 1650);
PAINT SKYBLUE (4150 1650);
FORCEPROP 1 LAST VALUE 33.2
J 2
(4150 1700);
DISPLAY 0.617021 (4150 1700);
PAINT SKYBLUE (4150 1700);
FORCEPROP 1 LAST TOLERANCE 1%
J 0
(4175 1700);
DISPLAY 0.617021 (4175 1700);
PAINT SKYBLUE (4175 1700);
FORCEPROP 1 LAST MATERIAL CHIP
J 0
(4175 1650);
DISPLAY 0.617021 (4175 1650);
PAINT SKYBLUE (4175 1650);
FORCEPROP 1 LAST LOCATION R4G19
J 0
(4125 1850);
DISPLAY 0.617021 (4125 1850);
PAINT AQUA (4125 1850);
FORCEPROP 1 LASTPIN (4275 1800) $PN 2
J 0
(4237 1812);
DISPLAY 0.617021 (4237 1812);
PAINT ORANGE (4237 1812);
FORCEPROP 1 LAST PART_NUMBER G21796-074
J 0
(4125 1900);
DISPLAY 0.617021 (4125 1900);
PAINT BLUE (4125 1900);
FORCEPROP 1 LAST PACK_TYPE 0402
J 0
(4425 1650);
DISPLAY 0.617021 (4425 1650);
PAINT SKYBLUE (4425 1650);
FORCEPROP 2 LAST SEC 1
J 0
(4125 2000);
DISPLAY 0.680851 (4125 2000);
PAINT MONO (4125 2000);
DISPLAY INVISIBLE (4125 2000);
FORCEPROP 2 LAST CDS_LIB mstr_discrete
J 0
(4175 1800);
PAINT MONO (4175 1800);
DISPLAY INVISIBLE (4175 1800);
FORCEPROP 2 LAST SEC_TYPE 0402
J 0
(4125 2000);
DISPLAY 1.021277 (4125 2000);
PAINT ORANGE (4125 2000);
DISPLAY INVISIBLE (4125 2000);
FORCEPROP 2 LAST CDS_LOCATION R4G19
J 0
(4125 1850);
DISPLAY 0.617021 (4125 1850);
PAINT AQUA (4125 1850);
DISPLAY INVISIBLE (4125 1850);
FORCEPROP 1 LAST PATH I54
J 0
(4125 1950);
DISPLAY 0.978723 (4125 1950);
PAINT WHITE (4125 1950);
DISPLAY INVISIBLE (4125 1950);
FORCEADD RES..1
R 1
(4700 1000);
FORCEPROP 1 LAST VALUE 51.1
R 1
J 2
(4800 975);
DISPLAY 0.617021 (4800 975);
PAINT SKYBLUE (4800 975);
FORCEPROP 1 LAST WATTAGE 1/16W
R 1
J 2
(4850 975);
DISPLAY 0.617021 (4850 975);
PAINT SKYBLUE (4850 975);
FORCEPROP 1 LAST MATERIAL CHIP
R 1
J 0
(4850 1000);
DISPLAY 0.617021 (4850 1000);
PAINT SKYBLUE (4850 1000);
FORCEPROP 1 LAST TOLERANCE 1.0%
R 1
J 0
(4800 1000);
DISPLAY 0.617021 (4800 1000);
PAINT SKYBLUE (4800 1000);
FORCEPROP 1 LAST PART_NUMBER G21796-208
R 1
J 0
(4600 950);
DISPLAY 0.617021 (4600 950);
PAINT BLUE (4600 950);
FORCEPROP 1 LAST LOCATION R6U16
R 1
J 0
(4650 950);
DISPLAY 0.617021 (4650 950);
PAINT AQUA (4650 950);
FORCEPROP 1 LAST PACK_TYPE 0402
R 1
J 0
(4850 1125);
DISPLAY 0.617021 (4850 1125);
PAINT SKYBLUE (4850 1125);
FORCEPROP 1 LAST PATH I55
R 1
J 0
(4550 950);
DISPLAY 0.978723 (4550 950);
PAINT WHITE (4550 950);
DISPLAY INVISIBLE (4550 950);
FORCEPROP 1 LASTPIN (4700 900) $PN 1
R 1
J 0
(4688 912);
DISPLAY 0.787234 (4688 912);
PAINT ORANGE (4688 912);
DISPLAY INVISIBLE (4688 912);
FORCEPROP 2 LAST CDS_LOCATION R6U16
R 1
J 0
(4650 950);
DISPLAY 0.617021 (4650 950);
PAINT AQUA (4650 950);
DISPLAY INVISIBLE (4650 950);
FORCEPROP 2 LAST CDS_LIB mstr_discrete
J 0
(4700 1000);
PAINT ORANGE (4700 1000);
DISPLAY INVISIBLE (4700 1000);
FORCEPROP 2 LAST $SEC 1
J 0
(4725 1125);
PAINT MONO (4725 1125);
DISPLAY INVISIBLE (4725 1125);
FORCEPROP 2 LAST CDS_SEC 1
J 0
(4725 1125);
PAINT MONO (4725 1125);
DISPLAY INVISIBLE (4725 1125);
FORCEPROP 1 LASTPIN (4700 1100) $PN 2
R 1
J 0
(4688 1062);
DISPLAY 0.787234 (4688 1062);
PAINT ORANGE (4688 1062);
DISPLAY INVISIBLE (4688 1062);
FORCEADD SHUNT..1
(4975 0);
FORCEPROP 1 LAST PART_NUMBER N_A
J 0
(4900 -90);
DISPLAY 0.617021 (4900 -90);
PAINT BLUE (4900 -90);
FORCEPROP 1 LASTPIN (4825 0) $PN 1
J 2
(4875 10);
DISPLAY 0.617021 (4875 10);
PAINT ORANGE (4875 10);
FORCEPROP 1 LAST LOCATION SH5U1
J 0
(4900 50);
DISPLAY 0.617021 (4900 50);
PAINT AQUA (4900 50);
FORCEPROP 1 LASTPIN (5125 0) $PN 2
J 0
(5085 10);
DISPLAY 0.617021 (5085 10);
PAINT ORANGE (5085 10);
FORCEPROP 1 LAST PIN_SHORT A:B
J 0
(4900 -250);
DISPLAY 1.021277 (4900 -250);
PAINT ORANGE (4900 -250);
DISPLAY INVISIBLE (4900 -250);
FORCEPROP 1 LAST PACK_TYPE SH0201
J 0
(4915 -185);
DISPLAY 0.978723 (4915 -185);
PAINT SKYBLUE (4915 -185);
DISPLAY INVISIBLE (4915 -185);
FORCEPROP 1 LAST MATERIAL EMPTY
J 0
(4900 -135);
DISPLAY 0.978723 (4900 -135);
PAINT RED (4900 -135);
DISPLAY INVISIBLE (4900 -135);
FORCEPROP 2 LAST CDS_LIB mstr_misc
J 0
(4975 0);
PAINT ORANGE (4975 0);
DISPLAY INVISIBLE (4975 0);
FORCEPROP 1 LAST PATH I56
J 0
(4925 100);
DISPLAY 0.978723 (4925 100);
PAINT ORANGE (4925 100);
DISPLAY INVISIBLE (4925 100);
FORCEPROP 0 LAST SEC 1
J 0
(4900 100);
DISPLAY 0.680851 (4900 100);
PAINT MONO (4900 100);
DISPLAY INVISIBLE (4900 100);
FORCEPROP 2 LAST SEC_TYPE SH0201
J 0
(4925 150);
DISPLAY 1.021277 (4925 150);
PAINT ORANGE (4925 150);
DISPLAY INVISIBLE (4925 150);
FORCEADD OFFPAGE..2
(5375 1800);
FORCEPROP 2 LAST $XR0 222 
J 0
(5564 1800);
DISPLAY 0.638298 (5564 1800);
PAINT MONO (5564 1800);
FORCEPROP 2 LAST $XR1 191 
J 0
(5684 1800);
DISPLAY 0.638298 (5684 1800);
PAINT MONO (5684 1800);
FORCEPROP 1 LAST COMMENT_BODY TRUE
J 0
(5330 1705);
DISPLAY 0.872340 (5330 1705);
PAINT GREEN (5330 1705);
DISPLAY INVISIBLE (5330 1705);
FORCEPROP 2 LAST CDS_LIB mstr_standard
J 0
(5375 1800);
DISPLAY 0.744681 (5375 1800);
PAINT MONO (5375 1800);
DISPLAY INVISIBLE (5375 1800);
FORCEPROP 2 LAST PATH I6
J 0
(5571 1840);
DISPLAY 1.021277 (5571 1840);
PAINT ORANGE (5571 1840);
DISPLAY INVISIBLE (5571 1840);
FORCEPROP 1 LAST OFFPAGE TRUE
J 0
(5700 1675);
DISPLAY 0.872340 (5700 1675);
PAINT GREEN (5700 1675);
DISPLAY INVISIBLE (5700 1675);
FORCEADD PVTT_ABC..1
(5525 1575);
FORCEPROP 3 LASTPIN (5525 1525) SIG_NAME PVTT_ABC\g
J 0
(5535 1535);
DISPLAY 0.659574 (5535 1535);
PAINT MONO (5535 1535);
DISPLAY INVISIBLE (5535 1535);
FORCEPROP 1 LAST BODY_TYPE PLUMBING
J 0
(5480 1532);
DISPLAY 0.340426 (5480 1532);
PAINT GREEN (5480 1532);
DISPLAY INVISIBLE (5480 1532);
FORCEPROP 1 LAST VOLTAGE 0.6V
J 0
(5480 1532);
DISPLAY 0.340426 (5480 1532);
PAINT SKYBLUE (5480 1532);
DISPLAY INVISIBLE (5480 1532);
FORCEPROP 2 LAST CDS_LIB mstr_symbols
J 0
(5525 1575);
PAINT ORANGE (5525 1575);
DISPLAY INVISIBLE (5525 1575);
FORCEPROP 1 LAST PATH I7
J 0
(5575 1600);
DISPLAY 0.872340 (5575 1600);
PAINT AQUA (5575 1600);
DISPLAY INVISIBLE (5575 1600);
FORCEPROP 1 LAST HDL_POWER PVTT_ABC
J 1
(5525 1625);
DISPLAY 0.872340 (5525 1625);
PAINT GREEN (5525 1625);
DISPLAY INVISIBLE (5525 1625);
FORCEADD GND..1
(4350 3075);
FORCEPROP 3 LASTPIN (4350 3125) SIG_NAME GND\g
J 0
(4360 3135);
DISPLAY 0.659574 (4360 3135);
PAINT MONO (4360 3135);
DISPLAY INVISIBLE (4360 3135);
FORCEPROP 2 LAST ROOM VTT_ABC_PWR_VR
J 0
(3800 3150);
PAINT ORANGE (3800 3150);
DISPLAY INVISIBLE (3800 3150);
FORCEPROP 2 LAST BOM_COST MEM_VRD_PVDDQ_AB
J 0
(4025 3150);
PAINT MONO (4025 3150);
DISPLAY INVISIBLE (4025 3150);
FORCEPROP 1 LAST SIZE 1B
J 0
(4425 3025);
DISPLAY 0.893617 (4425 3025);
PAINT GREEN (4425 3025);
DISPLAY INVISIBLE (4425 3025);
FORCEPROP 1 LAST BODY_TYPE PLUMBING
J 0
(4305 3032);
DISPLAY 0.340426 (4305 3032);
PAINT GREEN (4305 3032);
DISPLAY INVISIBLE (4305 3032);
FORCEPROP 1 LAST VOLTAGE 0.0V
J 0
(4305 3032);
DISPLAY 0.340426 (4305 3032);
PAINT SKYBLUE (4305 3032);
DISPLAY INVISIBLE (4305 3032);
FORCEPROP 1 LAST HDL_POWER GND
J 0
(4350 3225);
DISPLAY 0.893617 (4350 3225);
PAINT GREEN (4350 3225);
DISPLAY INVISIBLE (4350 3225);
FORCEPROP 2 LAST CDS_LIB mstr_symbols
J 0
(4350 3075);
PAINT ORANGE (4350 3075);
DISPLAY INVISIBLE (4350 3075);
FORCEPROP 1 LAST PATH I8
J 0
(4425 3075);
DISPLAY 0.872340 (4425 3075);
PAINT AQUA (4425 3075);
DISPLAY INVISIBLE (4425 3075);
FORCEADD CAD_NOTE..1
(5000 250);
FORCEPROP 0 LAST L1 SPOF
J 0
(4961 151);
DISPLAY 0.617021 (4961 151);
PAINT WHITE (4961 151);
FORCEPROP 2 LAST CDS_LIB mstr_symbols
J 0
(5000 250);
PAINT ORANGE (5000 250);
DISPLAY INVISIBLE (5000 250);
FORCEPROP 1 LAST COMMENT_BODY TRUE
J 0
(5025 350);
DISPLAY 0.978723 (5025 350);
PAINT ORANGE (5025 350);
DISPLAY INVISIBLE (5025 350);
FORCEADD CAD_NOTE..1
(2250 1575);
FORCEPROP 0 LAST L1 PLACE CLOSE TO CONTROLLER
J 0
(2068 1483);
DISPLAY 0.617021 (2068 1483);
PAINT WHITE (2068 1483);
FORCEPROP 1 LAST COMMENT_BODY TRUE
J 0
(2275 1675);
DISPLAY 0.978723 (2275 1675);
PAINT ORANGE (2275 1675);
DISPLAY INVISIBLE (2275 1675);
FORCEPROP 2 LAST CDS_LIB mstr_symbols
J 0
(2250 1575);
PAINT ORANGE (2250 1575);
DISPLAY INVISIBLE (2250 1575);
FORCEADD CAD_NOTE..1
(4725 -275);
FORCEPROP 0 LAST L2 OF PVTT PLANE
J 0
(4607 -422);
DISPLAY 0.617021 (4607 -422);
PAINT WHITE (4607 -422);
FORCEPROP 0 LAST L1 PLACE NEAR CENTER
J 0
(4607 -370);
DISPLAY 0.617021 (4607 -370);
PAINT WHITE (4607 -370);
FORCEPROP 2 LAST CDS_LIB mstr_symbols
J 0
(4725 -275);
PAINT ORANGE (4725 -275);
DISPLAY INVISIBLE (4725 -275);
FORCEPROP 1 LAST COMMENT_BODY TRUE
J 0
(4750 -175);
DISPLAY 0.978723 (4750 -175);
PAINT ORANGE (4750 -175);
DISPLAY INVISIBLE (4750 -175);
FORCEADD PRELIM..6
(1560 1040);
PAINT GRAY (1560 1040);
FORCEPROP 2 LAST CDS_LIB mstr_misc
J 0
(1560 1040);
PAINT ORANGE (1560 1040);
DISPLAY INVISIBLE (1560 1040);
FORCEPROP 1 LAST COMMENT_BODY TRUE
J 0
(1560 1040);
PAINT ORANGE (1560 1040);
DISPLAY INVISIBLE (1560 1040);
FORCEADD CAD_NOTE..1
(4825 3500);
FORCEPROP 2 LAST CDS_LIB mstr_symbols
J 0
(4825 3500);
PAINT ORANGE (4825 3500);
DISPLAY INVISIBLE (4825 3500);
FORCEPROP 1 LAST COMMENT_BODY TRUE
J 0
(4850 3600);
DISPLAY 0.978723 (4850 3600);
PAINT ORANGE (4850 3600);
DISPLAY INVISIBLE (4850 3600);
FORCEADD DNS..2
(-320 645);
PAINT RED (-320 645);
FORCEPROP 1 LAST COMMENT_BODY TRUE
R 1
J 0
(-245 420);
DISPLAY 0.872340 (-245 420);
PAINT GREEN (-245 420);
DISPLAY INVISIBLE (-245 420);
FORCEPROP 2 LAST CDS_LIB mstr_misc
J 0
(-320 645);
PAINT ORANGE (-320 645);
DISPLAY INVISIBLE (-320 645);
FORCEADD CAD_NOTE..1
(100 2750);
FORCEPROP 0 LAST L1 PLACE CLOSE TO CONTROLLER
J 0
(13 2658);
DISPLAY 0.617021 (13 2658);
PAINT WHITE (13 2658);
FORCEPROP 2 LAST CDS_LIB mstr_symbols
J 0
(100 2750);
PAINT ORANGE (100 2750);
DISPLAY INVISIBLE (100 2750);
FORCEPROP 1 LAST COMMENT_BODY TRUE
J 0
(125 2850);
DISPLAY 0.978723 (125 2850);
PAINT ORANGE (125 2850);
DISPLAY INVISIBLE (125 2850);
FORCEADD DNS..2
(-370 -405);
PAINT RED (-370 -405);
FORCEPROP 1 LAST COMMENT_BODY TRUE
R 1
J 0
(-295 -630);
DISPLAY 0.872340 (-295 -630);
PAINT GREEN (-295 -630);
DISPLAY INVISIBLE (-295 -630);
FORCEPROP 2 LAST CDS_LIB mstr_misc
J 0
(-370 -405);
PAINT ORANGE (-370 -405);
DISPLAY INVISIBLE (-370 -405);
FORCEADD DNS..3
(4980 -5);
PAINT RED (4980 -5);
FORCEPROP 1 LAST COMMENT_BODY TRUE
R 1
J 0
(5055 -230);
DISPLAY 0.872340 (5055 -230);
PAINT GREEN (5055 -230);
DISPLAY INVISIBLE (5055 -230);
FORCEPROP 2 LAST CDS_LIB mstr_misc
J 0
(4980 -5);
PAINT ORANGE (4980 -5);
DISPLAY INVISIBLE (4980 -5);
FORCEADD INTEL_CORP_BPAGE..1
(5975 -1075);
FORCEPROP 1 LAST CDS_CON_LAST_MODIFIED Tue Dec 01 11:52:26 2015
J 0
(4550 -750);
PAINT GREEN (4550 -750);
DISPLAY INVISIBLE (4550 -750);
FORCEPROP 1 LAST CUSTOM_TXT_CDS <CURRENT_DESIGN_SHEET> OF <TOTAL_DESIGN_SHEETS>
J 0
(5475 -1050);
PAINT GREEN (5475 -1050);
FORCEPROP 1 LAST CUSTOM_TXT_CDS <CON_LAST_MODIFIED>
J 0
(4050 -725);
PAINT GREEN (4050 -725);
FORCEPROP 2 LAST CUSTOM_TXT_CDS <XR_PAGE_TITLE>
J 0
(-1915 4175);
DISPLAY 0.638298 (-1915 4175);
PAINT PINK (-1915 4175);
DISPLAY INVISIBLE (-1915 4175);
FORCEPROP 1 LAST SCH_TITLE DDR VTT VR CHANNEL ABC
J 0
(-1975 -1025);
DISPLAY 1.212766 (-1975 -1025);
PAINT GREEN (-1975 -1025);
FORCEPROP 1 LAST SCH_ADDRESS1 2200 MISSION COLLEGE BLVD.
J 0
(2000 -950);
DISPLAY 0.617021 (2000 -950);
PAINT GREEN (2000 -950);
FORCEPROP 1 LAST SCH_ADDRESS2 P.O. BOX 58119
J 0
(2000 -1000);
DISPLAY 0.617021 (2000 -1000);
PAINT GREEN (2000 -1000);
FORCEPROP 1 LAST SCH_ADDRESS3 SANTA CLARA, CA 95052-8119
J 0
(2000 -1050);
DISPLAY 0.617021 (2000 -1050);
PAINT GREEN (2000 -1050);
FORCEPROP 1 LAST SCH_REV 2.420
J 0
(5725 -925);
DISPLAY 0.978723 (5725 -925);
PAINT YELLOW (5725 -925);
FORCEPROP 1 LAST SCH_DEPT BESD
J 1
(1525 -975);
DISPLAY 1.212766 (1525 -975);
PAINT YELLOW (1525 -975);
FORCEPROP 1 LAST SCH_NUMBER H4694802
J 0
(4675 -925);
DISPLAY 1.212766 (4675 -925);
PAINT YELLOW (4675 -925);
FORCEPROP 2 LAST PAGE_BORDER TRUE
J 0
(-1915 4175);
DISPLAY 0.659574 (-1915 4175);
PAINT PINK (-1915 4175);
DISPLAY INVISIBLE (-1915 4175);
FORCEPROP 2 LAST CDS_LIB mstr_symbols
J 0
(5975 -1075);
PAINT ORANGE (5975 -1075);
DISPLAY INVISIBLE (5975 -1075);
FORCEPROP 1 LAST COMMENT_BODY TRUE
J 0
(5987 -1063);
DISPLAY 0.446809 (5987 -1063);
PAINT GREEN (5987 -1063);
DISPLAY INVISIBLE (5987 -1063);
FORCEPROP 2 LAST CDS_XR_PAGE_TITLE CR-221 : @BASEBOARD_FAB2_LIB.BASEBOARD_FAB2(SCH_1):PAGE221
J 0
(-1915 4175);
DISPLAY 0.638298 (-1915 4175);
PAINT PINK (-1915 4175);
DISPLAY INVISIBLE (-1915 4175);
WIRE 16 -1 (4350 3550)(4350 3625);
WIRE 16 -1 (4350 3625)(3950 3625);
WIRE 16 -1 (3950 3550)(3950 3625);
WIRE 16 -1 (3600 3625)(3950 3625);
WIRE 16 -1 (3600 3625)(3600 3675);
WIRE 16 -1 (3600 3625)(3600 3550);
WIRE 16 -1 (3875 1425)(3875 1500);
WIRE 16 -1 (4700 900)(4700 775);
WIRE 16 -1 (4700 775)(3975 775);
WIRE 16 -1 (3975 775)(3975 925);
WIRE 16 -1 (3975 650)(3975 775);
WIRE 16 -1 (475 2150)(475 2250);
WIRE 16 -1 (475 1375)(475 1300);
WIRE 16 -1 (50 2225)(50 2150);
WIRE 16 -1 (1250 1300)(1100 1300);
WIRE 16 -1 (1100 1300)(1100 2525);
WIRE 16 -1 (475 2525)(1100 2525);
WIRE 16 -1 (475 2450)(475 2525);
WIRE 16 -1 (50 2525)(475 2525);
WIRE 16 -1 (50 2425)(50 2525);
WIRE 16 -1 (50 2525)(-1075 2525);
WIRE 16 -1 (-1075 2525)(-1075 1525);
WIRE 16 -1 (-1075 2525)(-1425 2525);
WIRE 16 -1 (-1425 2725)(-1425 2525);
WIRE 16 -1 (-875 1525)(-1075 1525);
WIRE 16 -1 (1850 900)(2000 900);
WIRE 16 -1 (2000 900)(2000 850);
WIRE 16 -1 (1850 850)(2000 850);
WIRE 16 -1 (2000 850)(2000 750);
WIRE 16 -1 (1850 750)(2000 750);
WIRE 16 -1 (2000 750)(2000 625);
WIRE 16 -1 (2375 625)(2375 725);
WIRE 16 -1 (-375 -575)(-375 -500);
WIRE 16 -1 (25 1750)(-325 1750);
WIRE 16 -1 (-550 1750)(-325 1750);
WIRE 16 -1 (-325 750)(-325 1750);
WIRE 16 -1 (-550 2000)(-550 1750);
WIRE 16 -1 (3500 2125)(3500 2225);
WIRE 16 -1 (325 900)(325 825);
WIRE 16 -1 (3975 1125)(3975 1300);
WIRE 16 -1 (3975 1300)(4700 1300);
WIRE 16 -1 (1850 1300)(3975 1300);
WIRE 16 -1 (4700 1100)(4700 1300);
WIRE 16 -1 (5525 1300)(4700 1300);
WIRE 16 -1 (5525 0)(5525 1300);
WIRE 16 -1 (5525 1525)(5525 1300);
WIRE 16 -1 (5125 0)(5525 0);
WIRE 16 -1 (3600 3350)(3600 3200);
WIRE 16 -1 (3600 3200)(3950 3200);
WIRE 16 -1 (3950 3350)(3950 3200);
WIRE 16 -1 (3950 3200)(4350 3200);
WIRE 16 -1 (4350 3350)(4350 3200);
WIRE 16 -1 (4350 3125)(4350 3200);
WIRE 16 2175 (-75 1225)(875 1225);
WIRE 16 2175 (-75 1225)(-75 2825);
WIRE 16 2175 (875 1225)(875 2825);
WIRE 16 2175 (-75 2825)(875 2825);
WIRE 16 2175 (5550 2800)(5550 3875);
WIRE 16 2175 (5550 2800)(3425 2800);
WIRE 16 2175 (5550 3875)(3425 3875);
WIRE 16 2175 (3425 2800)(3425 3875);
WIRE 16 -1 (5325 1800)(4275 1800);
FORCEPROP 2 LAST SIG_NAME PWRGD_PVTT_CPU0
J 0
(4698 1810);
DISPLAY 0.617021 (4698 1810);
PAINT ORANGE (4698 1810);
WIRE 16 2175 (5200 -450)(5200 125);
WIRE 16 2175 (4550 -450)(5200 -450);
WIRE 16 2175 (4550 125)(5200 125);
WIRE 16 2175 (4550 -450)(4550 125);
WIRE 16 273 (2100 3500)(2100 3000);
WIRE 16 273 (2100 3600)(2100 3500);
WIRE 16 273 (950 3500)(2100 3500);
WIRE 16 273 (2100 3000)(950 3000);
WIRE 16 273 (950 3000)(950 3500);
WIRE 16 273 (950 3500)(950 3600);
WIRE 16 273 (950 3600)(2100 3600);
WIRE 16 -1 (3875 1700)(3875 1800);
WIRE 16 -1 (4075 1800)(3875 1800);
WIRE 16 -1 (3875 1800)(3500 1800);
FORCEPROP 2 LAST SIG_NAME PWRGD_PVTT_ABC_CPU0_R
J 0
(3548 1810);
DISPLAY 0.617021 (3548 1810);
PAINT ORANGE (3548 1810);
FORCEPROP 2 LASTPROP $XRERR UNIQUE?
J 0
(3308 1810);
DISPLAY 0.638298 (3308 1810);
PAINT MONO (3308 1810);
DISPLAY INVISIBLE (3308 1810);
WIRE 16 -1 (3500 1800)(3500 1925);
WIRE 16 -1 (3500 1000)(3500 1800);
WIRE 16 -1 (1850 1000)(3500 1000);
WIRE 16 2175 (2050 1650)(2850 1650);
WIRE 16 2175 (2050 525)(2050 1650);
WIRE 16 2175 (2850 1650)(2850 525);
WIRE 16 2175 (2850 525)(2050 525);
WIRE 16 -1 (2375 925)(2375 1200);
WIRE 16 -1 (1850 1200)(2375 1200);
FORCEPROP 2 LAST SIG_NAME VR_PVTT_ABC_VREF
J 0
(1918 1210);
DISPLAY 0.617021 (1918 1210);
PAINT ORANGE (1918 1210);
FORCEPROP 2 LASTPROP $XRERR UNIQUE?
J 0
(1678 1210);
DISPLAY 0.638298 (1678 1210);
PAINT MONO (1678 1210);
DISPLAY INVISIBLE (1678 1210);
WIRE 16 -1 (1250 800)(1025 800);
WIRE 16 -1 (1025 800)(1025 1750);
WIRE 16 -1 (1025 1750)(475 1750);
WIRE 16 -1 (475 1575)(475 1750);
WIRE 16 -1 (225 1750)(475 1750);
FORCEPROP 2 LAST SIG_NAME VR_PVTT_ABC_BIAS
J 0
(308 1770);
DISPLAY 0.617021 (308 1770);
PAINT ORANGE (308 1770);
FORCEPROP 2 LASTPROP $XRERR UNIQUE?
J 0
(68 1770);
DISPLAY 0.638298 (68 1770);
PAINT MONO (68 1770);
DISPLAY INVISIBLE (68 1770);
WIRE 16 -1 (1250 950)(975 950);
WIRE 16 -1 (975 950)(975 0);
WIRE 16 -1 (975 0)(4825 0);
FORCEPROP 2 LAST SIG_NAME VR_PVTT_ABC_SNS
J 0
(1027 5);
DISPLAY 0.617021 (1027 5);
PAINT ORANGE (1027 5);
FORCEPROP 2 LASTPROP $XRERR UNIQUE?
J 0
(787 5);
DISPLAY 0.638298 (787 5);
PAINT MONO (787 5);
DISPLAY INVISIBLE (787 5);
WIRE 16 -1 (325 1100)(325 1150);
WIRE 16 -1 (325 1150)(1250 1150);
WIRE 16 -1 (-500 1150)(325 1150);
FORCEPROP 2 LAST SIG_NAME VSENSE_PVDDQ_ABC_VTT
J 0
(-66 1160);
DISPLAY 0.617021 (-66 1160);
PAINT ORANGE (-66 1160);
FORCEPROP 2 LASTPROP $XRERR UNIQUE?
J 0
(-306 1160);
DISPLAY 0.638298 (-306 1160);
PAINT MONO (-306 1160);
DISPLAY INVISIBLE (-306 1160);
WIRE 16 -1 (-500 1150)(-500 1525);
WIRE 16 -1 (-500 1525)(-675 1525);
WIRE 16 -1 (1250 1050)(575 1050);
FORCEPROP 2 LAST SIG_NAME FM_PVTT_ABC_EN_R
J 0
(-26 140);
DISPLAY 0.617021 (-26 140);
PAINT ORANGE (-26 140);
FORCEPROP 2 LASTPROP $XRERR UNIQUE?
J 0
(-266 140);
DISPLAY 0.638298 (-266 140);
PAINT MONO (-266 140);
DISPLAY INVISIBLE (-266 140);
WIRE 16 -1 (575 1050)(575 125);
WIRE 16 -1 (575 125)(-325 125);
WIRE 16 -1 (-325 125)(-325 550);
WIRE 16 -1 (-325 125)(-375 125);
WIRE 16 -1 (-425 125)(-375 125);
WIRE 16 -1 (-375 -300)(-375 125);
WIRE 16 -1 (-625 125)(-1350 125);
FORCEPROP 2 LAST SIG_NAME PWRGD_PVDDQ_ABC
J 0
(-1313 140);
DISPLAY 0.617021 (-1313 140);
PAINT ORANGE (-1313 140);
DOT 1 (-375 125);
DOT 1 (-325 125);
DOT 1 (-325 1750);
DOT 1 (-1075 2525);
DOT 1 (325 1150);
DOT 1 (475 1750);
DOT 1 (2000 750);
DOT 1 (2000 850);
DOT 1 (50 2525);
DOT 1 (475 2525);
DOT 1 (950 3500);
DOT 1 (3975 775);
DOT 1 (3500 1800);
DOT 1 (3975 1300);
DOT 1 (3875 1800);
DOT 1 (2100 3500);
DOT 1 (3950 3200);
DOT 1 (3600 3625);
DOT 1 (3950 3625);
DOT 1 (4700 1300);
DOT 1 (5525 1300);
DOT 1 (4350 3200);
FORCENOTE
ROOM = VTT_ABC_PWR_VR
(-1980 -851) 0;
DISPLAY LEFT (-1980 -851);
DISPLAY 1.255319 (-1980 -851);
PAINT PURPLE (-1980 -851);
FORCENOTE
BOM = MEM_VRD_VTT_ABC
(-1980 -926) 0;
DISPLAY LEFT (-1980 -926);
DISPLAY 1.255319 (-1980 -926);
PAINT PURPLE (-1980 -926);
FORCENOTE
CRTICAL: PLACE 0 OHM NEAR  VDDQ SENSE RESISTOR.
(-1780 1374) 0;
DISPLAY LEFT (-1780 1374);
PAINT PURPLE (-1780 1374);
FORCENOTE
AC & RIPPLE=+3.5/-7.3%
(994 3285) 0;
DISPLAY LEFT (994 3285);
DISPLAY 0.808511 (994 3285);
PAINT PURPLE (994 3285);
FORCENOTE
RIPPLE GUIDELINE= +/-1%
(994 3385) 0;
DISPLAY LEFT (994 3385);
DISPLAY 0.808511 (994 3385);
PAINT PURPLE (994 3385);
FORCENOTE
IOUT DI/DT=6A/US
(994 3085) 0;
DISPLAY LEFT (994 3085);
DISPLAY 0.808511 (994 3085);
PAINT PURPLE (994 3085);
FORCENOTE
DC TOL= +/-1.5%
(994 3335) 0;
DISPLAY LEFT (994 3335);
DISPLAY 0.808511 (994 3335);
PAINT PURPLE (994 3335);
FORCENOTE
IOUT TDC=+/-1.7A
(994 3185) 0;
DISPLAY LEFT (994 3185);
DISPLAY 0.808511 (994 3185);
PAINT PURPLE (994 3185);
FORCENOTE
VOUT=0.5 VDDQ
(994 3435) 0;
DISPLAY LEFT (994 3435);
DISPLAY 0.808511 (994 3435);
PAINT PURPLE (994 3435);
FORCENOTE
IOUT PEAK=+-/1.7A
(994 3235) 0;
DISPLAY LEFT (994 3235);
DISPLAY 0.808511 (994 3235);
PAINT PURPLE (994 3235);
FORCENOTE
IOUT STEP=+ 1.523A / - 1.546A
(994 3135) 0;
DISPLAY LEFT (994 3135);
DISPLAY 0.808511 (994 3135);
PAINT PURPLE (994 3135);
FORCENOTE
PVTT DDR SPECIFICATION:
(994 3535) 0;
DISPLAY LEFT (994 3535);
PAINT PURPLE (994 3535);
FORCENOTE
PLACE BETWEEN DIMMS
(4663 3371) 0;
DISPLAY LEFT (4663 3371);
DISPLAY 1.021277 (4663 3371);
PAINT PURPLE (4663 3371);
QUIT
